FILE_TYPE = MACRO_DRAWING;
SET COLOR_WIRE YELLOW;
SET COLOR_PROP ORANGE;
SET COLOR_DOT WHITE;
SET COLOR_ARC YELLOW;
SET COLOR_BODY GREEN;
SET COLOR_NOTE PURPLE;
SET PROP_DISPLAY VALUE;
SET PAGE_NUMBER P176;
FORCEADD UNIVERSAL_GND..1
(-9750 575);
FORCEPROP 3 LASTPIN (-9750 625) SIG_NAME GND\g
J 0
(-9740 635);
DISPLAY 0.659574 (-9740 635);
PAINT MONO (-9740 635);
DISPLAY INVISIBLE (-9740 635);
FORCEPROP 2 LAST CDS_LIB pure_quanta_power
J 0
(-9750 575);
PAINT MONO (-9750 575);
DISPLAY INVISIBLE (-9750 575);
FORCEPROP 1 LAST HDL_POWER GND
J 1
(-9725 500);
DISPLAY 0.872340 (-9725 500);
PAINT GREEN (-9725 500);
DISPLAY INVISIBLE (-9725 500);
FORCEPROP 1 LAST PATH I1
J 0
(-9675 575);
DISPLAY 0.872340 (-9675 575);
PAINT AQUA (-9675 575);
DISPLAY INVISIBLE (-9675 575);
FORCEADD Q_CAP..1
(-8875 1600);
FORCEPROP 1 LAST LOCATION PC80
J 0
(-8825 1700);
DISPLAY 0.489362 (-8825 1700);
PAINT SKYBLUE (-8825 1700);
FORCEPROP 0 LAST $SEC 1
J 0
(-8825 1750);
DISPLAY 0.680851 (-8825 1750);
PAINT MONO (-8825 1750);
DISPLAY INVISIBLE (-8825 1750);
FORCEPROP 0 LAST CDS_SEC 1
J 0
(-8825 1750);
DISPLAY 1.021277 (-8825 1750);
DISPLAY INVISIBLE (-8825 1750);
FORCEPROP 1 LASTPIN (-8875 1700) $PN 1
J 0
(-8865 1680);
DISPLAY 0.489362 (-8865 1680);
PAINT MONO (-8865 1680);
FORCEPROP 1 LASTPIN (-8875 1500) $PN 2
J 0
(-8865 1480);
DISPLAY 0.489362 (-8865 1480);
PAINT MONO (-8865 1480);
FORCEPROP 1 LAST PACK_TYPE C0402
J 0
(-8825 1400);
DISPLAY 0.489362 (-8825 1400);
PAINT SKYBLUE (-8825 1400);
FORCEPROP 1 LAST VOLTAGE 10V
J 0
(-8825 1600);
DISPLAY 0.489362 (-8825 1600);
PAINT SKYBLUE (-8825 1600);
FORCEPROP 1 LAST VALUE 2.2UF
J 0
(-8825 1650);
DISPLAY 0.489362 (-8825 1650);
PAINT SKYBLUE (-8825 1650);
FORCEPROP 1 LAST TOLERANCE 10%
J 0
(-8825 1550);
DISPLAY 0.489362 (-8825 1550);
PAINT SKYBLUE (-8825 1550);
FORCEPROP 1 LAST MATERIAL X6S
J 0
(-8825 1500);
DISPLAY 0.489362 (-8825 1500);
PAINT SKYBLUE (-8825 1500);
FORCEPROP 2 LAST CDS_LIB pure_quanta
J 0
(-8875 1600);
DISPLAY INVISIBLE (-8875 1600);
FORCEPROP 1 LAST PATH I10
J 0
(-8825 1750);
DISPLAY 0.978723 (-8825 1750);
PAINT WHITE (-8825 1750);
DISPLAY INVISIBLE (-8825 1750);
FORCEPROP 1 LAST PART_NUMBER CH5222KEB01
J 0
(-8825 1450);
DISPLAY 0.489362 (-8825 1450);
PAINT SKYBLUE (-8825 1450);
DISPLAY INVISIBLE (-8825 1450);
FORCEADD UNIVERSAL_GND..1
(-9625 3550);
FORCEPROP 3 LASTPIN (-9625 3600) SIG_NAME GND\g
J 0
(-9615 3610);
DISPLAY 0.659574 (-9615 3610);
PAINT MONO (-9615 3610);
DISPLAY INVISIBLE (-9615 3610);
FORCEPROP 2 LAST CDS_LIB pure_quanta_power
J 0
(-9625 3550);
PAINT MONO (-9625 3550);
DISPLAY INVISIBLE (-9625 3550);
FORCEPROP 1 LAST HDL_POWER GND
J 1
(-9600 3475);
DISPLAY 0.872340 (-9600 3475);
PAINT GREEN (-9600 3475);
DISPLAY INVISIBLE (-9600 3475);
FORCEPROP 1 LAST PATH I11
J 0
(-9550 3550);
DISPLAY 0.872340 (-9550 3550);
PAINT AQUA (-9550 3550);
DISPLAY INVISIBLE (-9550 3550);
FORCEADD Q_CAP..1
(-9625 3750);
FORCEPROP 1 LAST LOCATION PC84_1
J 0
(-9575 3850);
DISPLAY 0.489362 (-9575 3850);
PAINT SKYBLUE (-9575 3850);
FORCEPROP 0 LAST $SEC 1
J 0
(-9575 3875);
DISPLAY 0.680851 (-9575 3875);
PAINT MONO (-9575 3875);
DISPLAY INVISIBLE (-9575 3875);
FORCEPROP 0 LAST CDS_SEC 1
J 0
(-9375 3800);
DISPLAY 1.021277 (-9375 3800);
DISPLAY INVISIBLE (-9375 3800);
FORCEPROP 1 LASTPIN (-9625 3850) $PN 1
J 0
(-9615 3830);
DISPLAY 0.489362 (-9615 3830);
PAINT MONO (-9615 3830);
FORCEPROP 1 LASTPIN (-9625 3650) $PN 2
J 0
(-9615 3630);
DISPLAY 0.489362 (-9615 3630);
PAINT MONO (-9615 3630);
FORCEPROP 1 LAST PACK_TYPE 0402
J 0
(-9575 3550);
DISPLAY 0.489362 (-9575 3550);
PAINT SKYBLUE (-9575 3550);
FORCEPROP 1 LAST VOLTAGE 25V
J 0
(-9575 3750);
DISPLAY 0.489362 (-9575 3750);
PAINT SKYBLUE (-9575 3750);
FORCEPROP 1 LAST VALUE 0.1UF
J 0
(-9575 3800);
DISPLAY 0.489362 (-9575 3800);
PAINT SKYBLUE (-9575 3800);
FORCEPROP 1 LAST TOLERANCE 10%
J 0
(-9575 3700);
DISPLAY 0.489362 (-9575 3700);
PAINT SKYBLUE (-9575 3700);
FORCEPROP 1 LAST MATERIAL X7R
J 0
(-9575 3650);
DISPLAY 0.489362 (-9575 3650);
PAINT SKYBLUE (-9575 3650);
FORCEPROP 2 LAST CDS_LIB pure_quanta
J 0
(-9625 3750);
DISPLAY INVISIBLE (-9625 3750);
FORCEPROP 1 LAST PATH I12
J 0
(-9575 3900);
DISPLAY 0.978723 (-9575 3900);
PAINT WHITE (-9575 3900);
DISPLAY INVISIBLE (-9575 3900);
FORCEPROP 1 LAST PART_NUMBER CH4104K1B00
J 0
(-9575 3600);
DISPLAY 0.489362 (-9575 3600);
PAINT SKYBLUE (-9575 3600);
DISPLAY INVISIBLE (-9575 3600);
FORCEADD Q_RES..2
(-8875 2150);
FORCEPROP 1 LAST LOCATION PR80
J 0
(-8830 2275);
DISPLAY 0.489362 (-8830 2275);
PAINT SKYBLUE (-8830 2275);
FORCEPROP 0 LAST $SEC 1
J 0
(-8825 2325);
DISPLAY 0.680851 (-8825 2325);
PAINT MONO (-8825 2325);
DISPLAY INVISIBLE (-8825 2325);
FORCEPROP 0 LAST CDS_SEC 1
J 0
(-8825 2325);
DISPLAY 1.021277 (-8825 2325);
DISPLAY INVISIBLE (-8825 2325);
FORCEPROP 1 LASTPIN (-8875 2250) $PN 1
J 0
(-8870 2212);
DISPLAY 0.489362 (-8870 2212);
PAINT MONO (-8870 2212);
FORCEPROP 1 LASTPIN (-8875 2050) $PN 2
J 0
(-8870 2060);
DISPLAY 0.489362 (-8870 2060);
PAINT MONO (-8870 2060);
FORCEPROP 1 LAST MATERIAL CHIP
J 0
(-8825 2075);
DISPLAY 0.489362 (-8825 2075);
PAINT SKYBLUE (-8825 2075);
FORCEPROP 1 LAST TOLERANCE 1%
J 0
(-8825 2175);
DISPLAY 0.489362 (-8825 2175);
PAINT SKYBLUE (-8825 2175);
FORCEPROP 1 LAST VALUE 2.2
J 0
(-8825 2225);
DISPLAY 0.489362 (-8825 2225);
PAINT SKYBLUE (-8825 2225);
FORCEPROP 1 LAST PACK_TYPE 0402LF
J 0
(-8825 1975);
DISPLAY 0.489362 (-8825 1975);
PAINT SKYBLUE (-8825 1975);
FORCEPROP 1 LAST WATTAGE 1/16W
J 0
(-8825 2125);
DISPLAY 0.489362 (-8825 2125);
PAINT SKYBLUE (-8825 2125);
FORCEPROP 2 LAST CDS_LIB pure_quanta
J 0
(-8875 2150);
DISPLAY INVISIBLE (-8875 2150);
FORCEPROP 1 LAST PATH I13
J 0
(-8825 2325);
DISPLAY 0.978723 (-8825 2325);
PAINT WHITE (-8825 2325);
DISPLAY INVISIBLE (-8825 2325);
FORCEPROP 1 LAST PART_NUMBER CS-2202FB01
J 0
(-8825 2025);
DISPLAY 0.489362 (-8825 2025);
PAINT SKYBLUE (-8825 2025);
DISPLAY INVISIBLE (-8825 2025);
FORCEADD UNIVERSAL_GND..1
(-8525 1900);
FORCEPROP 3 LASTPIN (-8525 1950) SIG_NAME GND\g
J 0
(-8515 1960);
DISPLAY 0.659574 (-8515 1960);
PAINT MONO (-8515 1960);
DISPLAY INVISIBLE (-8515 1960);
FORCEPROP 2 LAST CDS_LIB pure_quanta_power
J 0
(-8525 1900);
DISPLAY INVISIBLE (-8525 1900);
FORCEPROP 1 LAST HDL_POWER GND
J 1
(-8500 1825);
DISPLAY 0.872340 (-8500 1825);
PAINT GREEN (-8500 1825);
DISPLAY INVISIBLE (-8500 1825);
FORCEPROP 1 LAST PATH I14
J 0
(-8450 1900);
DISPLAY 0.872340 (-8450 1900);
PAINT AQUA (-8450 1900);
DISPLAY INVISIBLE (-8450 1900);
FORCEADD Q_CAP..1
(-8525 2175);
FORCEPROP 1 LAST LOCATION PC82_C1P0_2
J 0
(-8475 2275);
DISPLAY 0.489362 (-8475 2275);
PAINT SKYBLUE (-8475 2275);
FORCEPROP 0 LAST $SEC 1
J 0
(-8475 2325);
DISPLAY 0.680851 (-8475 2325);
PAINT MONO (-8475 2325);
DISPLAY INVISIBLE (-8475 2325);
FORCEPROP 0 LAST CDS_SEC 1
J 0
(-8475 2325);
DISPLAY 1.021277 (-8475 2325);
DISPLAY INVISIBLE (-8475 2325);
FORCEPROP 1 LASTPIN (-8525 2275) $PN 1
J 0
(-8515 2255);
DISPLAY 0.489362 (-8515 2255);
PAINT MONO (-8515 2255);
FORCEPROP 1 LASTPIN (-8525 2075) $PN 2
J 0
(-8515 2055);
DISPLAY 0.489362 (-8515 2055);
PAINT MONO (-8515 2055);
FORCEPROP 1 LAST PACK_TYPE C0402
J 0
(-8475 1975);
DISPLAY 0.489362 (-8475 1975);
PAINT SKYBLUE (-8475 1975);
FORCEPROP 1 LAST VOLTAGE 10V
J 0
(-8475 2175);
DISPLAY 0.489362 (-8475 2175);
PAINT SKYBLUE (-8475 2175);
FORCEPROP 1 LAST TOLERANCE 10%
J 0
(-8475 2125);
DISPLAY 0.489362 (-8475 2125);
PAINT SKYBLUE (-8475 2125);
FORCEPROP 1 LAST MATERIAL X6S
J 0
(-8475 2075);
DISPLAY 0.489362 (-8475 2075);
PAINT SKYBLUE (-8475 2075);
FORCEPROP 1 LAST VALUE 2.2UF
J 0
(-8475 2225);
DISPLAY 0.489362 (-8475 2225);
PAINT SKYBLUE (-8475 2225);
FORCEPROP 2 LAST CDS_LIB pure_quanta
J 0
(-8525 2175);
DISPLAY INVISIBLE (-8525 2175);
FORCEPROP 1 LAST PATH I15
J 0
(-8475 2325);
DISPLAY 0.978723 (-8475 2325);
PAINT WHITE (-8475 2325);
DISPLAY INVISIBLE (-8475 2325);
FORCEPROP 1 LAST PART_NUMBER CH5222KEB01
J 0
(-8475 2025);
DISPLAY 0.489362 (-8475 2025);
PAINT SKYBLUE (-8475 2025);
DISPLAY INVISIBLE (-8475 2025);
FORCEADD VCC_CORE..1
(-8875 2575);
FORCEPROP 3 LASTPIN (-8875 2525) SIG_NAME PVDDCR_CPU1_P0_PVCC\g
J 0
(-8865 2535);
DISPLAY 0.659574 (-8865 2535);
PAINT MONO (-8865 2535);
DISPLAY INVISIBLE (-8865 2535);
FORCEPROP 1 LAST HDL_POWER PVDDCR_CPU1_P0_PVCC
J 1
(-8875 2625);
DISPLAY 0.489362 (-8875 2625);
PAINT GREEN (-8875 2625);
FORCEPROP 2 LAST CDS_LIB pure_quanta_power
J 0
(-8875 2575);
DISPLAY INVISIBLE (-8875 2575);
FORCEPROP 1 LAST PATH I16
J 0
(-8825 2600);
DISPLAY 0.872340 (-8825 2600);
PAINT AQUA (-8825 2600);
DISPLAY INVISIBLE (-8825 2600);
FORCEADD UNIVERSAL_GND..1
(-9125 3400);
FORCEPROP 3 LASTPIN (-9125 3450) SIG_NAME GND\g
J 0
(-9115 3460);
DISPLAY 0.659574 (-9115 3460);
PAINT MONO (-9115 3460);
DISPLAY INVISIBLE (-9115 3460);
FORCEPROP 2 LAST CDS_LIB pure_quanta_power
J 0
(-9125 3400);
PAINT MONO (-9125 3400);
DISPLAY INVISIBLE (-9125 3400);
FORCEPROP 1 LAST HDL_POWER GND
J 1
(-9100 3325);
DISPLAY 0.872340 (-9100 3325);
PAINT GREEN (-9100 3325);
DISPLAY INVISIBLE (-9100 3325);
FORCEPROP 1 LAST PATH I17
J 0
(-9050 3400);
DISPLAY 0.872340 (-9050 3400);
PAINT AQUA (-9050 3400);
DISPLAY INVISIBLE (-9050 3400);
FORCEADD Q_RES..2
R 2
(-9125 3625);
FORCEPROP 1 LAST LOCATION PR78
J 2
(-9170 3750);
DISPLAY 0.489362 (-9170 3750);
PAINT SKYBLUE (-9170 3750);
FORCEPROP 0 LAST $SEC 1
J 0
(-9150 3800);
DISPLAY 0.680851 (-9150 3800);
PAINT MONO (-9150 3800);
DISPLAY INVISIBLE (-9150 3800);
FORCEPROP 0 LAST CDS_SEC 1
J 0
(-9150 3800);
DISPLAY 1.021277 (-9150 3800);
DISPLAY INVISIBLE (-9150 3800);
FORCEPROP 1 LASTPIN (-9125 3725) $PN 1
J 2
(-9130 3687);
DISPLAY 0.489362 (-9130 3687);
PAINT MONO (-9130 3687);
FORCEPROP 1 LASTPIN (-9125 3525) $PN 2
J 2
(-9130 3535);
DISPLAY 0.489362 (-9130 3535);
PAINT MONO (-9130 3535);
FORCEPROP 1 LAST WATTAGE 1/16W
J 2
(-9165 3600);
DISPLAY 0.489362 (-9165 3600);
PAINT SKYBLUE (-9165 3600);
FORCEPROP 1 LAST MATERIAL EMPTY
J 2
(-9165 3550);
DISPLAY 0.489362 (-9165 3550);
PAINT RED (-9165 3550);
FORCEPROP 1 LAST TOLERANCE 1%
J 2
(-9170 3650);
DISPLAY 0.489362 (-9170 3650);
PAINT SKYBLUE (-9170 3650);
FORCEPROP 1 LAST VALUE 8.87K
J 2
(-9170 3700);
DISPLAY 0.489362 (-9170 3700);
PAINT SKYBLUE (-9170 3700);
FORCEPROP 1 LAST PACK_TYPE 0402LF
J 2
(-9165 3450);
DISPLAY 0.489362 (-9165 3450);
PAINT SKYBLUE (-9165 3450);
FORCEPROP 2 LAST CDS_LIB pure_quanta
J 2
(-9125 3625);
DISPLAY INVISIBLE (-9125 3625);
FORCEPROP 1 LAST PATH I18
J 2
(-9175 3800);
DISPLAY 0.978723 (-9175 3800);
PAINT WHITE (-9175 3800);
DISPLAY INVISIBLE (-9175 3800);
FORCEPROP 1 LAST PART_NUMBER CS28872FB01
J 2
(-9165 3500);
DISPLAY 0.489362 (-9165 3500);
PAINT SKYBLUE (-9165 3500);
DISPLAY INVISIBLE (-9165 3500);
FORCEADD OFFPAGE..1
(-8550 3525);
FORCEPROP 2 LAST $XR0 200 
J 0
(-8802 3525);
DISPLAY 0.638298 (-8802 3525);
PAINT MONO (-8802 3525);
FORCEPROP 2 LAST CDS_LIB standard
J 0
(-8550 3525);
DISPLAY INVISIBLE (-8550 3525);
FORCEPROP 1 LAST OFFPAGE TRUE
J 0
(-8225 3400);
DISPLAY 0.872340 (-8225 3400);
PAINT GREEN (-8225 3400);
DISPLAY INVISIBLE (-8225 3400);
FORCEPROP 1 LAST COMMENT_BODY TRUE
J 0
(-8425 3425);
DISPLAY 0.872340 (-8425 3425);
PAINT GREEN (-8425 3425);
DISPLAY INVISIBLE (-8425 3425);
FORCEPROP 2 LAST PATH I19
J 0
(-8800 3575);
DISPLAY 0.680851 (-8800 3575);
DISPLAY INVISIBLE (-8800 3575);
FORCEADD Q_CAP..1
(-9750 850);
FORCEPROP 1 LAST LOCATION PC83_2
J 0
(-9700 900);
DISPLAY 0.489362 (-9700 900);
PAINT SKYBLUE (-9700 900);
FORCEPROP 0 LAST $SEC 1
J 0
(-9700 975);
DISPLAY 0.680851 (-9700 975);
PAINT MONO (-9700 975);
DISPLAY INVISIBLE (-9700 975);
FORCEPROP 0 LAST CDS_SEC 1
J 0
(-9500 900);
DISPLAY 1.021277 (-9500 900);
DISPLAY INVISIBLE (-9500 900);
FORCEPROP 1 LASTPIN (-9750 950) $PN 1
J 0
(-9740 930);
DISPLAY 0.489362 (-9740 930);
PAINT MONO (-9740 930);
FORCEPROP 1 LASTPIN (-9750 750) $PN 2
J 0
(-9740 730);
DISPLAY 0.489362 (-9740 730);
PAINT MONO (-9740 730);
FORCEPROP 1 LAST PACK_TYPE 0402
J 0
(-9700 600);
DISPLAY 0.489362 (-9700 600);
PAINT SKYBLUE (-9700 600);
FORCEPROP 1 LAST VOLTAGE 25V
J 0
(-9700 800);
DISPLAY 0.489362 (-9700 800);
PAINT SKYBLUE (-9700 800);
FORCEPROP 1 LAST VALUE 0.1UF
J 0
(-9700 850);
DISPLAY 0.489362 (-9700 850);
PAINT SKYBLUE (-9700 850);
FORCEPROP 1 LAST TOLERANCE 10%
J 0
(-9700 750);
DISPLAY 0.489362 (-9700 750);
PAINT SKYBLUE (-9700 750);
FORCEPROP 1 LAST MATERIAL X7R
J 0
(-9700 700);
DISPLAY 0.489362 (-9700 700);
PAINT SKYBLUE (-9700 700);
FORCEPROP 2 LAST CDS_LIB pure_quanta
J 0
(-9750 850);
DISPLAY INVISIBLE (-9750 850);
FORCEPROP 1 LAST PATH I2
J 0
(-9700 1000);
DISPLAY 0.978723 (-9700 1000);
PAINT WHITE (-9700 1000);
DISPLAY INVISIBLE (-9700 1000);
FORCEPROP 1 LAST PART_NUMBER CH4104K1B00
J 0
(-9700 650);
DISPLAY 0.489362 (-9700 650);
PAINT SKYBLUE (-9700 650);
DISPLAY INVISIBLE (-9700 650);
FORCEADD OFFPAGE..5
(-8550 3625);
FORCEPROP 2 LAST $XR3 200 
J 0
(-8955 3589);
DISPLAY 0.638298 (-8955 3589);
PAINT MONO (-8955 3589);
FORCEPROP 2 LAST $XR2 203 
J 0
(-8835 3589);
DISPLAY 0.638298 (-8835 3589);
PAINT MONO (-8835 3589);
FORCEPROP 2 LAST $XR1 202 
J 0
(-8955 3625);
DISPLAY 0.638298 (-8955 3625);
PAINT MONO (-8955 3625);
FORCEPROP 2 LAST $XR0 201 
J 0
(-8835 3625);
DISPLAY 0.638298 (-8835 3625);
PAINT MONO (-8835 3625);
FORCEPROP 2 LAST CDS_LIB standard
J 0
(-8550 3625);
DISPLAY INVISIBLE (-8550 3625);
FORCEPROP 1 LAST OFFPAGE TRUE
J 0
(-8225 3500);
DISPLAY 0.872340 (-8225 3500);
PAINT GREEN (-8225 3500);
DISPLAY INVISIBLE (-8225 3500);
FORCEPROP 1 LAST COMMENT_BODY TRUE
J 0
(-8450 3550);
DISPLAY 0.872340 (-8450 3550);
PAINT GREEN (-8450 3550);
DISPLAY INVISIBLE (-8450 3550);
FORCEPROP 2 LAST PATH I20
J 0
(-8800 3675);
DISPLAY 0.680851 (-8800 3675);
DISPLAY INVISIBLE (-8800 3675);
FORCEADD Q_RES..1
R 1
(-9625 5450);
FORCEPROP 1 LAST LOCATION PR442
J 0
(-9600 5600);
DISPLAY 0.489362 (-9600 5600);
PAINT SKYBLUE (-9600 5600);
FORCEPROP 0 LAST $SEC 1
R 1
J 0
(-9600 5625);
DISPLAY 0.680851 (-9600 5625);
PAINT MONO (-9600 5625);
DISPLAY INVISIBLE (-9600 5625);
FORCEPROP 0 LAST CDS_SEC 1
R 1
J 0
(-9600 5625);
DISPLAY 1.021277 (-9600 5625);
DISPLAY INVISIBLE (-9600 5625);
FORCEPROP 1 LASTPIN (-9625 5350) $PN 1
R 1
J 0
(-9637 5362);
DISPLAY 0.787234 (-9637 5362);
PAINT MONO (-9637 5362);
DISPLAY INVISIBLE (-9637 5362);
FORCEPROP 1 LASTPIN (-9625 5550) $PN 2
R 1
J 0
(-9637 5512);
DISPLAY 0.787234 (-9637 5512);
PAINT MONO (-9637 5512);
DISPLAY INVISIBLE (-9637 5512);
FORCEPROP 1 LAST WATTAGE 1/16W
J 0
(-9600 5450);
DISPLAY 0.489362 (-9600 5450);
PAINT SKYBLUE (-9600 5450);
FORCEPROP 1 LAST MATERIAL CHIP
J 0
(-9600 5400);
DISPLAY 0.489362 (-9600 5400);
PAINT SKYBLUE (-9600 5400);
FORCEPROP 1 LAST TOLERANCE 5%
J 0
(-9600 5500);
DISPLAY 0.489362 (-9600 5500);
PAINT SKYBLUE (-9600 5500);
FORCEPROP 1 LAST VALUE 0
J 2
(-9575 5550);
DISPLAY 0.489362 (-9575 5550);
PAINT SKYBLUE (-9575 5550);
FORCEPROP 1 LAST PACK_TYPE 0402LF
J 0
(-9600 5300);
DISPLAY 0.489362 (-9600 5300);
PAINT SKYBLUE (-9600 5300);
FORCEPROP 2 LAST CDS_LIB pure_quanta
J 0
(-9625 5450);
DISPLAY INVISIBLE (-9625 5450);
FORCEPROP 1 LAST PATH I21
R 1
J 0
(-9775 5400);
DISPLAY 0.978723 (-9775 5400);
PAINT WHITE (-9775 5400);
DISPLAY INVISIBLE (-9775 5400);
FORCEPROP 1 LAST PART_NUMBER CS00002JB13
J 0
(-9600 5350);
DISPLAY 0.489362 (-9600 5350);
PAINT SKYBLUE (-9600 5350);
DISPLAY INVISIBLE (-9600 5350);
FORCEADD VCC_CORE..1
(-9625 5650);
FORCEPROP 3 LASTPIN (-9625 5600) SIG_NAME P5V_AUX\g
J 0
(-9615 5610);
DISPLAY 0.659574 (-9615 5610);
PAINT MONO (-9615 5610);
DISPLAY INVISIBLE (-9615 5610);
FORCEPROP 1 LAST HDL_POWER P5V_AUX
J 1
(-9625 5700);
DISPLAY 0.489362 (-9625 5700);
PAINT GREEN (-9625 5700);
FORCEPROP 2 LAST CDS_LIB pure_quanta_power
J 0
(-9625 5650);
DISPLAY INVISIBLE (-9625 5650);
FORCEPROP 1 LAST PATH I22
J 0
(-9575 5675);
DISPLAY 0.872340 (-9575 5675);
PAINT AQUA (-9575 5675);
DISPLAY INVISIBLE (-9575 5675);
FORCEADD UNIVERSAL_GND..1
(-8975 4375);
FORCEPROP 3 LASTPIN (-8975 4425) SIG_NAME GND\g
J 0
(-8965 4435);
DISPLAY 0.659574 (-8965 4435);
PAINT MONO (-8965 4435);
DISPLAY INVISIBLE (-8965 4435);
FORCEPROP 2 LAST CDS_LIB pure_quanta_power
J 0
(-8975 4375);
DISPLAY INVISIBLE (-8975 4375);
FORCEPROP 1 LAST HDL_POWER GND
J 1
(-8950 4300);
DISPLAY 0.872340 (-8950 4300);
PAINT GREEN (-8950 4300);
DISPLAY INVISIBLE (-8950 4300);
FORCEPROP 1 LAST PATH I23
J 0
(-8900 4375);
DISPLAY 0.872340 (-8900 4375);
PAINT AQUA (-8900 4375);
DISPLAY INVISIBLE (-8900 4375);
FORCEADD Q_CAP..1
(-8975 4575);
FORCEPROP 1 LAST LOCATION PC79
J 0
(-8925 4675);
DISPLAY 0.489362 (-8925 4675);
PAINT SKYBLUE (-8925 4675);
FORCEPROP 0 LAST $SEC 1
J 0
(-8925 4725);
DISPLAY 0.680851 (-8925 4725);
PAINT MONO (-8925 4725);
DISPLAY INVISIBLE (-8925 4725);
FORCEPROP 0 LAST CDS_SEC 1
J 0
(-8925 4725);
DISPLAY 1.021277 (-8925 4725);
DISPLAY INVISIBLE (-8925 4725);
FORCEPROP 1 LASTPIN (-8975 4675) $PN 1
J 0
(-8965 4655);
DISPLAY 0.489362 (-8965 4655);
PAINT MONO (-8965 4655);
FORCEPROP 1 LASTPIN (-8975 4475) $PN 2
J 0
(-8965 4455);
DISPLAY 0.489362 (-8965 4455);
PAINT MONO (-8965 4455);
FORCEPROP 1 LAST PACK_TYPE C0402
J 0
(-8925 4375);
DISPLAY 0.489362 (-8925 4375);
PAINT SKYBLUE (-8925 4375);
FORCEPROP 1 LAST VOLTAGE 10V
J 0
(-8925 4575);
DISPLAY 0.489362 (-8925 4575);
PAINT SKYBLUE (-8925 4575);
FORCEPROP 1 LAST VALUE 2.2UF
J 0
(-8925 4625);
DISPLAY 0.489362 (-8925 4625);
PAINT SKYBLUE (-8925 4625);
FORCEPROP 1 LAST TOLERANCE 10%
J 0
(-8925 4525);
DISPLAY 0.489362 (-8925 4525);
PAINT SKYBLUE (-8925 4525);
FORCEPROP 1 LAST MATERIAL X6S
J 0
(-8925 4475);
DISPLAY 0.489362 (-8925 4475);
PAINT SKYBLUE (-8925 4475);
FORCEPROP 2 LAST CDS_LIB pure_quanta
J 0
(-8975 4575);
DISPLAY INVISIBLE (-8975 4575);
FORCEPROP 1 LAST PATH I24
J 0
(-8925 4725);
DISPLAY 0.978723 (-8925 4725);
PAINT WHITE (-8925 4725);
DISPLAY INVISIBLE (-8925 4725);
FORCEPROP 1 LAST PART_NUMBER CH5222KEB01
J 0
(-8925 4425);
DISPLAY 0.489362 (-8925 4425);
PAINT SKYBLUE (-8925 4425);
DISPLAY INVISIBLE (-8925 4425);
FORCEADD OFFPAGE..1
(-8550 4025);
FORCEPROP 2 LAST $XR5 206 
J 0
(-9402 4025);
DISPLAY 0.638298 (-9402 4025);
PAINT MONO (-9402 4025);
FORCEPROP 2 LAST $XR4 205 
J 0
(-9282 4025);
DISPLAY 0.638298 (-9282 4025);
PAINT MONO (-9282 4025);
FORCEPROP 2 LAST $XR3 203 
J 0
(-9162 4025);
DISPLAY 0.638298 (-9162 4025);
PAINT MONO (-9162 4025);
FORCEPROP 2 LAST $XR2 202 
J 0
(-9042 4025);
DISPLAY 0.638298 (-9042 4025);
PAINT MONO (-9042 4025);
FORCEPROP 2 LAST $XR1 201 
J 0
(-8922 4025);
DISPLAY 0.638298 (-8922 4025);
PAINT MONO (-8922 4025);
FORCEPROP 2 LAST $XR0 200 
J 0
(-8802 4025);
DISPLAY 0.638298 (-8802 4025);
PAINT MONO (-8802 4025);
FORCEPROP 2 LAST CDS_LIB standard
J 0
(-8550 4025);
DISPLAY INVISIBLE (-8550 4025);
FORCEPROP 1 LAST OFFPAGE TRUE
J 0
(-8225 3900);
DISPLAY 0.872340 (-8225 3900);
PAINT GREEN (-8225 3900);
DISPLAY INVISIBLE (-8225 3900);
FORCEPROP 1 LAST COMMENT_BODY TRUE
J 0
(-8425 3925);
DISPLAY 0.872340 (-8425 3925);
PAINT GREEN (-8425 3925);
DISPLAY INVISIBLE (-8425 3925);
FORCEPROP 2 LAST PATH I25
J 0
(-8800 4075);
DISPLAY 0.680851 (-8800 4075);
DISPLAY INVISIBLE (-8800 4075);
FORCEADD OFFPAGE..5
(-8550 4125);
FORCEPROP 2 LAST $XR0 200 
J 0
(-8835 4125);
DISPLAY 0.638298 (-8835 4125);
PAINT MONO (-8835 4125);
FORCEPROP 2 LAST CDS_LIB standard
J 0
(-8550 4125);
DISPLAY INVISIBLE (-8550 4125);
FORCEPROP 1 LAST OFFPAGE TRUE
J 0
(-8225 4000);
DISPLAY 0.872340 (-8225 4000);
PAINT GREEN (-8225 4000);
DISPLAY INVISIBLE (-8225 4000);
FORCEPROP 1 LAST COMMENT_BODY TRUE
J 0
(-8450 4050);
DISPLAY 0.872340 (-8450 4050);
PAINT GREEN (-8450 4050);
DISPLAY INVISIBLE (-8450 4050);
FORCEPROP 2 LAST PATH I26
J 0
(-8800 4175);
DISPLAY 0.680851 (-8800 4175);
DISPLAY INVISIBLE (-8800 4175);
FORCEADD Q_RES..1
R 1
(-9275 5450);
FORCEPROP 1 LAST LOCATION PR443
J 0
(-9225 5600);
DISPLAY 0.489362 (-9225 5600);
PAINT SKYBLUE (-9225 5600);
FORCEPROP 0 LAST $SEC 1
R 1
J 0
(-9225 5625);
DISPLAY 0.680851 (-9225 5625);
PAINT MONO (-9225 5625);
DISPLAY INVISIBLE (-9225 5625);
FORCEPROP 0 LAST CDS_SEC 1
R 1
J 0
(-9225 5625);
DISPLAY 1.021277 (-9225 5625);
DISPLAY INVISIBLE (-9225 5625);
FORCEPROP 1 LASTPIN (-9275 5350) $PN 1
R 1
J 0
(-9287 5362);
DISPLAY 0.787234 (-9287 5362);
PAINT MONO (-9287 5362);
DISPLAY INVISIBLE (-9287 5362);
FORCEPROP 1 LASTPIN (-9275 5550) $PN 2
R 1
J 0
(-9287 5512);
DISPLAY 0.787234 (-9287 5512);
PAINT MONO (-9287 5512);
DISPLAY INVISIBLE (-9287 5512);
FORCEPROP 1 LAST WATTAGE 1/16W
J 0
(-9225 5450);
DISPLAY 0.489362 (-9225 5450);
PAINT SKYBLUE (-9225 5450);
FORCEPROP 1 LAST MATERIAL EMPTY
J 0
(-9225 5400);
DISPLAY 0.489362 (-9225 5400);
PAINT RED (-9225 5400);
FORCEPROP 1 LAST TOLERANCE 5%
J 0
(-9225 5500);
DISPLAY 0.489362 (-9225 5500);
PAINT SKYBLUE (-9225 5500);
FORCEPROP 1 LAST VALUE 0
J 2
(-9200 5550);
DISPLAY 0.489362 (-9200 5550);
PAINT SKYBLUE (-9200 5550);
FORCEPROP 1 LAST PACK_TYPE 0402LF
J 0
(-9225 5300);
DISPLAY 0.489362 (-9225 5300);
PAINT SKYBLUE (-9225 5300);
FORCEPROP 2 LAST CDS_LIB pure_quanta
J 0
(-9275 5450);
DISPLAY INVISIBLE (-9275 5450);
FORCEPROP 1 LAST PATH I27
R 1
J 0
(-9425 5400);
DISPLAY 0.978723 (-9425 5400);
PAINT WHITE (-9425 5400);
DISPLAY INVISIBLE (-9425 5400);
FORCEPROP 1 LAST PART_NUMBER CS00002JB13
J 0
(-9225 5350);
DISPLAY 0.489362 (-9225 5350);
PAINT SKYBLUE (-9225 5350);
DISPLAY INVISIBLE (-9225 5350);
FORCEADD VCC_CORE..1
(-9275 5650);
FORCEPROP 3 LASTPIN (-9275 5600) SIG_NAME P3V3_AUX\g
J 0
(-9265 5610);
DISPLAY 0.659574 (-9265 5610);
PAINT MONO (-9265 5610);
DISPLAY INVISIBLE (-9265 5610);
FORCEPROP 1 LAST HDL_POWER P3V3_AUX
J 1
(-9275 5700);
DISPLAY 0.489362 (-9275 5700);
PAINT GREEN (-9275 5700);
FORCEPROP 2 LAST CDS_LIB pure_quanta_power
J 0
(-9275 5650);
DISPLAY INVISIBLE (-9275 5650);
FORCEPROP 1 LAST PATH I28
J 0
(-9225 5675);
DISPLAY 0.872340 (-9225 5675);
PAINT AQUA (-9225 5675);
DISPLAY INVISIBLE (-9225 5675);
FORCEADD Q_RES..2
(-8975 5050);
FORCEPROP 1 LAST LOCATION PR79
J 0
(-8930 5175);
DISPLAY 0.489362 (-8930 5175);
PAINT SKYBLUE (-8930 5175);
FORCEPROP 0 LAST $SEC 1
J 0
(-8925 5225);
DISPLAY 0.680851 (-8925 5225);
PAINT MONO (-8925 5225);
DISPLAY INVISIBLE (-8925 5225);
FORCEPROP 0 LAST CDS_SEC 1
J 0
(-8925 5225);
DISPLAY 1.021277 (-8925 5225);
DISPLAY INVISIBLE (-8925 5225);
FORCEPROP 1 LASTPIN (-8975 5150) $PN 1
J 0
(-8970 5112);
DISPLAY 0.489362 (-8970 5112);
PAINT MONO (-8970 5112);
FORCEPROP 1 LASTPIN (-8975 4950) $PN 2
J 0
(-8970 4960);
DISPLAY 0.489362 (-8970 4960);
PAINT MONO (-8970 4960);
FORCEPROP 1 LAST WATTAGE 1/16W
J 0
(-8925 5025);
DISPLAY 0.489362 (-8925 5025);
PAINT SKYBLUE (-8925 5025);
FORCEPROP 1 LAST MATERIAL CHIP
J 0
(-8925 4975);
DISPLAY 0.489362 (-8925 4975);
PAINT SKYBLUE (-8925 4975);
FORCEPROP 1 LAST TOLERANCE 1%
J 0
(-8925 5075);
DISPLAY 0.489362 (-8925 5075);
PAINT SKYBLUE (-8925 5075);
FORCEPROP 1 LAST VALUE 2.2
J 0
(-8925 5125);
DISPLAY 0.489362 (-8925 5125);
PAINT SKYBLUE (-8925 5125);
FORCEPROP 1 LAST PACK_TYPE 0402LF
J 0
(-8925 4875);
DISPLAY 0.489362 (-8925 4875);
PAINT SKYBLUE (-8925 4875);
FORCEPROP 2 LAST CDS_LIB pure_quanta
J 0
(-8975 5050);
DISPLAY INVISIBLE (-8975 5050);
FORCEPROP 1 LAST PATH I29
J 0
(-8925 5225);
DISPLAY 0.978723 (-8925 5225);
PAINT WHITE (-8925 5225);
DISPLAY INVISIBLE (-8925 5225);
FORCEPROP 1 LAST PART_NUMBER CS-2202FB01
J 0
(-8925 4925);
DISPLAY 0.489362 (-8925 4925);
PAINT SKYBLUE (-8925 4925);
DISPLAY INVISIBLE (-8925 4925);
FORCEADD UNIVERSAL_GND..1
(-9150 450);
FORCEPROP 3 LASTPIN (-9150 500) SIG_NAME GND\g
J 0
(-9140 510);
DISPLAY 0.659574 (-9140 510);
PAINT MONO (-9140 510);
DISPLAY INVISIBLE (-9140 510);
FORCEPROP 2 LAST CDS_LIB pure_quanta_power
J 0
(-9150 450);
PAINT MONO (-9150 450);
DISPLAY INVISIBLE (-9150 450);
FORCEPROP 1 LAST HDL_POWER GND
J 1
(-9125 375);
DISPLAY 0.872340 (-9125 375);
PAINT GREEN (-9125 375);
DISPLAY INVISIBLE (-9125 375);
FORCEPROP 1 LAST PATH I3
J 0
(-9075 450);
DISPLAY 0.872340 (-9075 450);
PAINT AQUA (-9075 450);
DISPLAY INVISIBLE (-9075 450);
FORCEADD Q_CAP..1
(-8625 5075);
FORCEPROP 1 LAST LOCATION PC81_C1P0_1
J 0
(-8575 5175);
DISPLAY 0.489362 (-8575 5175);
PAINT SKYBLUE (-8575 5175);
FORCEPROP 0 LAST $SEC 1
J 0
(-8575 5225);
DISPLAY 0.680851 (-8575 5225);
PAINT MONO (-8575 5225);
DISPLAY INVISIBLE (-8575 5225);
FORCEPROP 0 LAST CDS_SEC 1
J 0
(-8575 5225);
DISPLAY 1.021277 (-8575 5225);
DISPLAY INVISIBLE (-8575 5225);
FORCEPROP 1 LASTPIN (-8625 5175) $PN 1
J 0
(-8615 5155);
DISPLAY 0.489362 (-8615 5155);
PAINT MONO (-8615 5155);
FORCEPROP 1 LASTPIN (-8625 4975) $PN 2
J 0
(-8615 4955);
DISPLAY 0.489362 (-8615 4955);
PAINT MONO (-8615 4955);
FORCEPROP 1 LAST PACK_TYPE C0402
J 0
(-8575 4875);
DISPLAY 0.489362 (-8575 4875);
PAINT SKYBLUE (-8575 4875);
FORCEPROP 1 LAST VOLTAGE 10V
J 0
(-8575 5075);
DISPLAY 0.489362 (-8575 5075);
PAINT SKYBLUE (-8575 5075);
FORCEPROP 1 LAST VALUE 2.2UF
J 0
(-8575 5125);
DISPLAY 0.489362 (-8575 5125);
PAINT SKYBLUE (-8575 5125);
FORCEPROP 1 LAST TOLERANCE 10%
J 0
(-8575 5025);
DISPLAY 0.489362 (-8575 5025);
PAINT SKYBLUE (-8575 5025);
FORCEPROP 1 LAST MATERIAL X6S
J 0
(-8575 4975);
DISPLAY 0.489362 (-8575 4975);
PAINT SKYBLUE (-8575 4975);
FORCEPROP 2 LAST CDS_LIB pure_quanta
J 0
(-8625 5075);
DISPLAY INVISIBLE (-8625 5075);
FORCEPROP 1 LAST PATH I30
J 0
(-8575 5225);
DISPLAY 0.978723 (-8575 5225);
PAINT WHITE (-8575 5225);
DISPLAY INVISIBLE (-8575 5225);
FORCEPROP 1 LAST PART_NUMBER CH5222KEB01
J 0
(-8575 4925);
DISPLAY 0.489362 (-8575 4925);
PAINT SKYBLUE (-8575 4925);
DISPLAY INVISIBLE (-8575 4925);
FORCEADD UNIVERSAL_GND..1
(-8625 4825);
FORCEPROP 3 LASTPIN (-8625 4875) SIG_NAME GND\g
J 0
(-8615 4885);
DISPLAY 0.659574 (-8615 4885);
PAINT MONO (-8615 4885);
DISPLAY INVISIBLE (-8615 4885);
FORCEPROP 2 LAST CDS_LIB pure_quanta_power
J 0
(-8625 4825);
DISPLAY INVISIBLE (-8625 4825);
FORCEPROP 1 LAST HDL_POWER GND
J 1
(-8600 4750);
DISPLAY 0.872340 (-8600 4750);
PAINT GREEN (-8600 4750);
DISPLAY INVISIBLE (-8600 4750);
FORCEPROP 1 LAST PATH I31
J 0
(-8550 4825);
DISPLAY 0.872340 (-8550 4825);
PAINT AQUA (-8550 4825);
DISPLAY INVISIBLE (-8550 4825);
FORCEADD VCC_CORE..1
(-8775 5650);
FORCEPROP 3 LASTPIN (-8775 5600) SIG_NAME PVDDCR_CPU1_P0_PVCC\g
J 0
(-8765 5610);
DISPLAY 0.659574 (-8765 5610);
PAINT MONO (-8765 5610);
DISPLAY INVISIBLE (-8765 5610);
FORCEPROP 1 LAST HDL_POWER PVDDCR_CPU1_P0_PVCC
J 1
(-8775 5700);
DISPLAY 0.489362 (-8775 5700);
PAINT GREEN (-8775 5700);
FORCEPROP 2 LAST CDS_LIB pure_quanta_power
J 0
(-8775 5650);
DISPLAY INVISIBLE (-8775 5650);
FORCEPROP 1 LAST PATH I32
J 0
(-8725 5675);
DISPLAY 0.872340 (-8725 5675);
PAINT AQUA (-8725 5675);
DISPLAY INVISIBLE (-8725 5675);
FORCEADD ISL99390FRZTR5935..1
(-7225 1175);
FORCEPROP 1 LAST LOCATION PU2
J 0
(-7525 2050);
DISPLAY 0.489362 (-7525 2050);
PAINT SKYBLUE (-7525 2050);
FORCEPROP 0 LAST $SEC 1
J 0
(-7525 2225);
DISPLAY 0.680851 (-7525 2225);
PAINT MONO (-7525 2225);
DISPLAY INVISIBLE (-7525 2225);
FORCEPROP 0 LAST CDS_SEC 1
J 0
(-7525 2225);
DISPLAY 1.021277 (-7525 2225);
DISPLAY INVISIBLE (-7525 2225);
FORCEPROP 0 LASTPIN (-6825 725) $PN 2
J 0
(-6815 735);
DISPLAY 0.489362 (-6815 735);
PAINT MONO (-6815 735);
FORCEPROP 0 LASTPIN (-6825 1525) $PN 33
J 0
(-6815 1535);
DISPLAY 0.489362 (-6815 1535);
PAINT MONO (-6815 1535);
FORCEPROP 0 LASTPIN (-7675 925) $PN 31
J 2
(-7685 935);
DISPLAY 0.489362 (-7685 935);
PAINT MONO (-7685 935);
FORCEPROP 0 LASTPIN (-7675 1325) $PN 35
J 2
(-7685 1335);
DISPLAY 0.489362 (-7685 1335);
PAINT MONO (-7685 1335);
FORCEPROP 0 LASTPIN (-6825 875) $PN 6
J 0
(-6815 885);
DISPLAY 0.489362 (-6815 885);
PAINT MONO (-6815 885);
FORCEPROP 0 LASTPIN (-6825 825) $PN 41
J 0
(-6815 835);
DISPLAY 0.489362 (-6815 835);
PAINT MONO (-6815 835);
FORCEPROP 0 LASTPIN (-7675 1175) $PN 38
J 2
(-7685 1185);
DISPLAY 0.489362 (-7685 1185);
PAINT MONO (-7685 1185);
FORCEPROP 0 LASTPIN (-7675 875) $PN 37
J 2
(-7685 885);
DISPLAY 0.489362 (-7685 885);
PAINT MONO (-7685 885);
FORCEPROP 0 LASTPIN (-6825 675) $PN 5
J 0
(-6815 685);
DISPLAY 0.489362 (-6815 685);
PAINT MONO (-6815 685);
FORCEPROP 0 LASTPIN (-6825 625) $PN 7_9-20_24
J 0
(-6815 635);
DISPLAY 0.489362 (-6815 635);
PAINT MONO (-6815 635);
FORCEPROP 0 LASTPIN (-6825 575) $PN 40
J 0
(-6815 585);
DISPLAY 0.489362 (-6815 585);
PAINT MONO (-6815 585);
FORCEPROP 0 LASTPIN (-6825 1275) $PN 32
J 0
(-6815 1285);
DISPLAY 0.489362 (-6815 1285);
PAINT MONO (-6815 1285);
FORCEPROP 0 LASTPIN (-7675 1825) $PN 4
J 2
(-7685 1835);
DISPLAY 0.489362 (-7685 1835);
PAINT MONO (-7685 1835);
FORCEPROP 0 LASTPIN (-7675 575) $PN 34
J 2
(-7685 585);
DISPLAY 0.489362 (-7685 585);
PAINT MONO (-7685 585);
FORCEPROP 0 LASTPIN (-7675 1075) $PN 39
J 2
(-7685 1085);
DISPLAY 0.489362 (-7685 1085);
PAINT MONO (-7685 1085);
FORCEPROP 0 LASTPIN (-6825 1175) $PN 10_19
J 0
(-6815 1185);
DISPLAY 0.489362 (-6815 1185);
PAINT MONO (-6815 1185);
FORCEPROP 0 LASTPIN (-7675 675) $PN 36
J 2
(-7685 685);
DISPLAY 0.489362 (-7685 685);
PAINT MONO (-7685 685);
FORCEPROP 0 LASTPIN (-7675 1525) $PN 3
J 2
(-7685 1535);
DISPLAY 0.489362 (-7685 1535);
PAINT MONO (-7685 1535);
FORCEPROP 0 LASTPIN (-6825 1825) $PN 25_29
J 0
(-6815 1835);
DISPLAY 0.489362 (-6815 1835);
PAINT MONO (-6815 1835);
FORCEPROP 0 LASTPIN (-6825 1775) $PN 30
J 0
(-6815 1785);
DISPLAY 0.489362 (-6815 1785);
PAINT MONO (-6815 1785);
FORCEPROP 0 LASTPIN (-6825 925) $PN 1
J 0
(-6815 935);
DISPLAY 0.489362 (-6815 935);
PAINT MONO (-6815 935);
FORCEPROP 1 LAST MATERIAL IC
J 0
(-7525 1900);
DISPLAY 0.489362 (-7525 1900);
PAINT SKYBLUE (-7525 1900);
FORCEPROP 2 LAST PART_TYPE SMLF
J 0
(-7525 2175);
DISPLAY 0.808511 (-7525 2175);
FORCEPROP 2 LAST VALUE ISL99390FRZ-TR5935
J 0
(-7525 2125);
DISPLAY 0.489362 (-7525 2125);
PAINT SKYBLUE (-7525 2125);
FORCEPROP 1 LAST CDS_LMAN_SYM_OUTLINE -300,700,250,-650
J 0
(-7225 1175);
DISPLAY 0.468085 (-7225 1175);
PAINT GREEN (-7225 1175);
DISPLAY INVISIBLE (-7225 1175);
FORCEPROP 1 LAST NEEDS_NO_SIZE TRUE
J 0
(-7225 1175);
DISPLAY 0.723404 (-7225 1175);
PAINT GREEN (-7225 1175);
DISPLAY INVISIBLE (-7225 1175);
FORCEPROP 2 LAST CDS_LIB pure_quanta
J 0
(-7225 1175);
DISPLAY INVISIBLE (-7225 1175);
FORCEPROP 1 LAST PATH I33
J 0
(-7225 1175);
DISPLAY 0.723404 (-7225 1175);
PAINT GREEN (-7225 1175);
DISPLAY INVISIBLE (-7225 1175);
FORCEPROP 1 LAST PART_NUMBER AL099390004
J 0
(-7525 1975);
DISPLAY 0.489362 (-7525 1975);
PAINT SKYBLUE (-7525 1975);
DISPLAY INVISIBLE (-7525 1975);
FORCEADD UNIVERSAL_GND..1
(-6575 450);
FORCEPROP 3 LASTPIN (-6575 500) SIG_NAME GND\g
J 0
(-6565 510);
DISPLAY 0.659574 (-6565 510);
PAINT MONO (-6565 510);
DISPLAY INVISIBLE (-6565 510);
FORCEPROP 2 LAST CDS_LIB pure_quanta_power
J 0
(-6575 450);
PAINT MONO (-6575 450);
DISPLAY INVISIBLE (-6575 450);
FORCEPROP 1 LAST HDL_POWER GND
J 1
(-6550 375);
DISPLAY 0.872340 (-6550 375);
PAINT GREEN (-6550 375);
DISPLAY INVISIBLE (-6550 375);
FORCEPROP 1 LAST PATH I34
J 0
(-6500 450);
DISPLAY 0.872340 (-6500 450);
PAINT AQUA (-6500 450);
DISPLAY INVISIBLE (-6500 450);
FORCEADD ISL99390FRZTR5935..1
(-7200 4125);
FORCEPROP 1 LAST LOCATION PU13
J 0
(-7500 5000);
DISPLAY 0.489362 (-7500 5000);
PAINT SKYBLUE (-7500 5000);
FORCEPROP 0 LAST $SEC 1
J 0
(-7500 5175);
DISPLAY 0.680851 (-7500 5175);
PAINT MONO (-7500 5175);
DISPLAY INVISIBLE (-7500 5175);
FORCEPROP 2 LAST CDS_SEC 1
J 0
(-7500 5175);
DISPLAY 1.021277 (-7500 5175);
DISPLAY INVISIBLE (-7500 5175);
FORCEPROP 0 LASTPIN (-6800 3675) $PN 2
J 0
(-6790 3685);
DISPLAY 0.489362 (-6790 3685);
PAINT MONO (-6790 3685);
FORCEPROP 0 LASTPIN (-6800 4475) $PN 33
J 0
(-6790 4485);
DISPLAY 0.489362 (-6790 4485);
PAINT MONO (-6790 4485);
FORCEPROP 0 LASTPIN (-7650 3875) $PN 31
J 2
(-7660 3885);
DISPLAY 0.489362 (-7660 3885);
PAINT MONO (-7660 3885);
FORCEPROP 0 LASTPIN (-7650 4275) $PN 35
J 2
(-7660 4285);
DISPLAY 0.489362 (-7660 4285);
PAINT MONO (-7660 4285);
FORCEPROP 0 LASTPIN (-6800 3825) $PN 6
J 0
(-6790 3835);
DISPLAY 0.489362 (-6790 3835);
PAINT MONO (-6790 3835);
FORCEPROP 0 LASTPIN (-6800 3775) $PN 41
J 0
(-6790 3785);
DISPLAY 0.489362 (-6790 3785);
PAINT MONO (-6790 3785);
FORCEPROP 0 LASTPIN (-7650 4125) $PN 38
J 2
(-7660 4135);
DISPLAY 0.489362 (-7660 4135);
PAINT MONO (-7660 4135);
FORCEPROP 0 LASTPIN (-7650 3825) $PN 37
J 2
(-7660 3835);
DISPLAY 0.489362 (-7660 3835);
PAINT MONO (-7660 3835);
FORCEPROP 0 LASTPIN (-6800 3625) $PN 5
J 0
(-6790 3635);
DISPLAY 0.489362 (-6790 3635);
PAINT MONO (-6790 3635);
FORCEPROP 0 LASTPIN (-6800 3575) $PN 7_9-20_24
J 0
(-6790 3585);
DISPLAY 0.489362 (-6790 3585);
PAINT MONO (-6790 3585);
FORCEPROP 0 LASTPIN (-6800 3525) $PN 40
J 0
(-6790 3535);
DISPLAY 0.489362 (-6790 3535);
PAINT MONO (-6790 3535);
FORCEPROP 0 LASTPIN (-6800 4225) $PN 32
J 0
(-6790 4235);
DISPLAY 0.489362 (-6790 4235);
PAINT MONO (-6790 4235);
FORCEPROP 0 LASTPIN (-7650 4775) $PN 4
J 2
(-7660 4785);
DISPLAY 0.489362 (-7660 4785);
PAINT MONO (-7660 4785);
FORCEPROP 0 LASTPIN (-7650 3525) $PN 34
J 2
(-7660 3535);
DISPLAY 0.489362 (-7660 3535);
PAINT MONO (-7660 3535);
FORCEPROP 0 LASTPIN (-7650 4025) $PN 39
J 2
(-7660 4035);
DISPLAY 0.489362 (-7660 4035);
PAINT MONO (-7660 4035);
FORCEPROP 0 LASTPIN (-6800 4125) $PN 10_19
J 0
(-6790 4135);
DISPLAY 0.489362 (-6790 4135);
PAINT MONO (-6790 4135);
FORCEPROP 0 LASTPIN (-7650 3625) $PN 36
J 2
(-7660 3635);
DISPLAY 0.489362 (-7660 3635);
PAINT MONO (-7660 3635);
FORCEPROP 0 LASTPIN (-7650 4475) $PN 3
J 2
(-7660 4485);
DISPLAY 0.489362 (-7660 4485);
PAINT MONO (-7660 4485);
FORCEPROP 0 LASTPIN (-6800 4775) $PN 25_29
J 0
(-6790 4785);
DISPLAY 0.489362 (-6790 4785);
PAINT MONO (-6790 4785);
FORCEPROP 0 LASTPIN (-6800 4725) $PN 30
J 0
(-6790 4735);
DISPLAY 0.489362 (-6790 4735);
PAINT MONO (-6790 4735);
FORCEPROP 0 LASTPIN (-6800 3875) $PN 1
J 0
(-6790 3885);
DISPLAY 0.489362 (-6790 3885);
PAINT MONO (-6790 3885);
FORCEPROP 1 LAST MATERIAL IC
J 0
(-7500 4850);
DISPLAY 0.489362 (-7500 4850);
PAINT SKYBLUE (-7500 4850);
FORCEPROP 2 LAST PART_TYPE SMLF
J 0
(-7500 5125);
DISPLAY 0.808511 (-7500 5125);
FORCEPROP 2 LAST VALUE ISL99390FRZ-TR5935
J 0
(-7500 5075);
DISPLAY 0.489362 (-7500 5075);
PAINT SKYBLUE (-7500 5075);
FORCEPROP 1 LAST CDS_LMAN_SYM_OUTLINE -300,700,250,-650
J 0
(-7200 4125);
DISPLAY 0.468085 (-7200 4125);
PAINT GREEN (-7200 4125);
DISPLAY INVISIBLE (-7200 4125);
FORCEPROP 1 LAST NEEDS_NO_SIZE TRUE
J 0
(-7200 4125);
DISPLAY 0.723404 (-7200 4125);
PAINT GREEN (-7200 4125);
DISPLAY INVISIBLE (-7200 4125);
FORCEPROP 2 LAST CDS_LIB pure_quanta
J 0
(-7200 4125);
DISPLAY INVISIBLE (-7200 4125);
FORCEPROP 1 LAST PATH I35
J 0
(-7200 4125);
DISPLAY 0.723404 (-7200 4125);
PAINT GREEN (-7200 4125);
DISPLAY INVISIBLE (-7200 4125);
FORCEPROP 1 LAST PART_NUMBER AL099390004
J 0
(-7500 4925);
DISPLAY 0.489362 (-7500 4925);
PAINT SKYBLUE (-7500 4925);
DISPLAY INVISIBLE (-7500 4925);
FORCEADD UNIVERSAL_GND..1
(-6550 3400);
FORCEPROP 3 LASTPIN (-6550 3450) SIG_NAME GND\g
J 0
(-6540 3460);
DISPLAY 0.659574 (-6540 3460);
PAINT MONO (-6540 3460);
DISPLAY INVISIBLE (-6540 3460);
FORCEPROP 2 LAST CDS_LIB pure_quanta_power
J 0
(-6550 3400);
PAINT MONO (-6550 3400);
DISPLAY INVISIBLE (-6550 3400);
FORCEPROP 1 LAST HDL_POWER GND
J 1
(-6525 3325);
DISPLAY 0.872340 (-6525 3325);
PAINT GREEN (-6525 3325);
DISPLAY INVISIBLE (-6525 3325);
FORCEPROP 1 LAST PATH I36
J 0
(-6475 3400);
DISPLAY 0.872340 (-6475 3400);
PAINT AQUA (-6475 3400);
DISPLAY INVISIBLE (-6475 3400);
FORCEADD Q_CAP..1
(-6400 2075);
FORCEPROP 1 LAST LOCATION PC86_2
J 0
(-6350 2225);
DISPLAY 0.489362 (-6350 2225);
PAINT SKYBLUE (-6350 2225);
FORCEPROP 0 LAST $SEC 1
J 0
(-6350 2225);
DISPLAY 0.680851 (-6350 2225);
PAINT MONO (-6350 2225);
DISPLAY INVISIBLE (-6350 2225);
FORCEPROP 0 LAST CDS_SEC 1
J 0
(-6350 2225);
DISPLAY 1.021277 (-6350 2225);
DISPLAY INVISIBLE (-6350 2225);
FORCEPROP 1 LASTPIN (-6400 2175) $PN 1
J 0
(-6390 2155);
DISPLAY 0.489362 (-6390 2155);
PAINT MONO (-6390 2155);
FORCEPROP 1 LASTPIN (-6400 1975) $PN 2
J 0
(-6390 1955);
DISPLAY 0.489362 (-6390 1955);
PAINT MONO (-6390 1955);
FORCEPROP 1 LAST MATERIAL X7R
J 0
(-6350 2025);
DISPLAY 0.489362 (-6350 2025);
PAINT SKYBLUE (-6350 2025);
FORCEPROP 1 LAST PACK_TYPE 0402
J 0
(-6350 1975);
DISPLAY 0.489362 (-6350 1975);
PAINT SKYBLUE (-6350 1975);
FORCEPROP 1 LAST VOLTAGE 25V
J 0
(-6350 2125);
DISPLAY 0.489362 (-6350 2125);
PAINT SKYBLUE (-6350 2125);
FORCEPROP 1 LAST VALUE 0.1UF
J 0
(-6350 2175);
DISPLAY 0.489362 (-6350 2175);
PAINT SKYBLUE (-6350 2175);
FORCEPROP 1 LAST TOLERANCE 10%
J 0
(-6350 2075);
DISPLAY 0.489362 (-6350 2075);
PAINT SKYBLUE (-6350 2075);
FORCEPROP 2 LAST CDS_LIB pure_quanta
J 0
(-6400 2075);
DISPLAY INVISIBLE (-6400 2075);
FORCEPROP 1 LAST PATH I37
J 0
(-6350 2225);
DISPLAY 0.978723 (-6350 2225);
PAINT WHITE (-6350 2225);
DISPLAY INVISIBLE (-6350 2225);
FORCEPROP 1 LAST PART_NUMBER CH4104K1B00
J 0
(-6350 1925);
DISPLAY 0.489362 (-6350 1925);
PAINT SKYBLUE (-6350 1925);
DISPLAY INVISIBLE (-6350 1925);
FORCEADD UNIVERSAL_GND..1
(-5875 325);
FORCEPROP 3 LASTPIN (-5875 375) SIG_NAME GND\g
J 0
(-5865 385);
DISPLAY 0.659574 (-5865 385);
PAINT MONO (-5865 385);
DISPLAY INVISIBLE (-5865 385);
FORCEPROP 2 LAST CDS_LIB pure_quanta_power
J 0
(-5875 325);
DISPLAY INVISIBLE (-5875 325);
FORCEPROP 1 LAST HDL_POWER GND
J 1
(-5850 250);
DISPLAY 0.872340 (-5850 250);
PAINT GREEN (-5850 250);
DISPLAY INVISIBLE (-5850 250);
FORCEPROP 1 LAST PATH I38
J 0
(-5800 325);
DISPLAY 0.872340 (-5800 325);
PAINT AQUA (-5800 325);
DISPLAY INVISIBLE (-5800 325);
FORCEADD Q_RES..2
(-5875 550);
FORCEPROP 1 LAST LOCATION PR507
J 0
(-5830 675);
DISPLAY 0.489362 (-5830 675);
PAINT SKYBLUE (-5830 675);
FORCEPROP 0 LAST $SEC 1
J 0
(-5825 725);
DISPLAY 0.680851 (-5825 725);
PAINT MONO (-5825 725);
DISPLAY INVISIBLE (-5825 725);
FORCEPROP 0 LAST CDS_SEC 1
J 0
(-5825 725);
DISPLAY 1.021277 (-5825 725);
DISPLAY INVISIBLE (-5825 725);
FORCEPROP 1 LASTPIN (-5875 650) $PN 1
J 0
(-5870 612);
DISPLAY 0.489362 (-5870 612);
PAINT MONO (-5870 612);
FORCEPROP 1 LASTPIN (-5875 450) $PN 2
J 0
(-5870 460);
DISPLAY 0.489362 (-5870 460);
PAINT MONO (-5870 460);
FORCEPROP 1 LAST PACK_TYPE 0402LF
J 0
(-5835 375);
DISPLAY 0.489362 (-5835 375);
PAINT SKYBLUE (-5835 375);
FORCEPROP 1 LAST VALUE 1.5
J 0
(-5830 625);
DISPLAY 0.489362 (-5830 625);
PAINT SKYBLUE (-5830 625);
FORCEPROP 1 LAST TOLERANCE 1%
J 0
(-5830 575);
DISPLAY 0.489362 (-5830 575);
PAINT SKYBLUE (-5830 575);
FORCEPROP 1 LAST WATTAGE 1/8W
J 0
(-5835 525);
DISPLAY 0.489362 (-5835 525);
PAINT SKYBLUE (-5835 525);
FORCEPROP 1 LAST MATERIAL EMPTY
J 0
(-5835 475);
DISPLAY 0.489362 (-5835 475);
PAINT RED (-5835 475);
FORCEPROP 2 LAST CDS_LIB pure_quanta
J 0
(-5875 550);
DISPLAY INVISIBLE (-5875 550);
FORCEPROP 1 LAST PATH I39
J 0
(-5825 725);
DISPLAY 0.978723 (-5825 725);
PAINT WHITE (-5825 725);
DISPLAY INVISIBLE (-5825 725);
FORCEPROP 1 LAST PART_NUMBER CS-1504FB00
J 0
(-5835 425);
DISPLAY 0.489362 (-5835 425);
PAINT SKYBLUE (-5835 425);
DISPLAY INVISIBLE (-5835 425);
FORCEADD Q_RES..2
R 2
(-9150 675);
FORCEPROP 1 LAST LOCATION PR77
J 2
(-9195 800);
DISPLAY 0.489362 (-9195 800);
PAINT SKYBLUE (-9195 800);
FORCEPROP 0 LAST $SEC 1
J 0
(-9175 850);
DISPLAY 0.680851 (-9175 850);
PAINT MONO (-9175 850);
DISPLAY INVISIBLE (-9175 850);
FORCEPROP 0 LAST CDS_SEC 1
J 0
(-9175 850);
DISPLAY 1.021277 (-9175 850);
DISPLAY INVISIBLE (-9175 850);
FORCEPROP 1 LASTPIN (-9150 775) $PN 1
J 2
(-9155 737);
DISPLAY 0.489362 (-9155 737);
PAINT MONO (-9155 737);
FORCEPROP 1 LASTPIN (-9150 575) $PN 2
J 2
(-9155 585);
DISPLAY 0.489362 (-9155 585);
PAINT MONO (-9155 585);
FORCEPROP 1 LAST PACK_TYPE 0402LF
J 2
(-9190 500);
DISPLAY 0.489362 (-9190 500);
PAINT SKYBLUE (-9190 500);
FORCEPROP 1 LAST VALUE 8.87K
J 2
(-9195 750);
DISPLAY 0.489362 (-9195 750);
PAINT SKYBLUE (-9195 750);
FORCEPROP 1 LAST TOLERANCE 1%
J 2
(-9195 700);
DISPLAY 0.489362 (-9195 700);
PAINT SKYBLUE (-9195 700);
FORCEPROP 1 LAST MATERIAL EMPTY
J 2
(-9190 600);
DISPLAY 0.489362 (-9190 600);
PAINT RED (-9190 600);
FORCEPROP 1 LAST WATTAGE 1/16W
J 2
(-9190 650);
DISPLAY 0.489362 (-9190 650);
PAINT SKYBLUE (-9190 650);
FORCEPROP 2 LAST CDS_LIB pure_quanta
J 2
(-9150 675);
DISPLAY INVISIBLE (-9150 675);
FORCEPROP 1 LAST PATH I4
J 2
(-9200 850);
DISPLAY 0.978723 (-9200 850);
PAINT WHITE (-9200 850);
DISPLAY INVISIBLE (-9200 850);
FORCEPROP 1 LAST PART_NUMBER CS28872FB01
J 2
(-9190 550);
DISPLAY 0.489362 (-9190 550);
PAINT SKYBLUE (-9190 550);
DISPLAY INVISIBLE (-9190 550);
FORCEADD Q_RES..1
(-5975 1525);
FORCEPROP 1 LAST LOCATION PR81
J 0
(-6200 1600);
DISPLAY 0.489362 (-6200 1600);
PAINT SKYBLUE (-6200 1600);
FORCEPROP 0 LAST $SEC 1
J 0
(-5700 1625);
DISPLAY 0.680851 (-5700 1625);
PAINT MONO (-5700 1625);
DISPLAY INVISIBLE (-5700 1625);
FORCEPROP 0 LAST CDS_SEC 1
J 0
(-5700 1625);
DISPLAY 1.021277 (-5700 1625);
DISPLAY INVISIBLE (-5700 1625);
FORCEPROP 1 LASTPIN (-6075 1525) $PN 1
J 0
(-6063 1537);
DISPLAY 0.787234 (-6063 1537);
PAINT MONO (-6063 1537);
DISPLAY INVISIBLE (-6063 1537);
FORCEPROP 1 LASTPIN (-5875 1525) $PN 2
J 0
(-5913 1537);
DISPLAY 0.787234 (-5913 1537);
PAINT MONO (-5913 1537);
DISPLAY INVISIBLE (-5913 1537);
FORCEPROP 1 LAST PACK_TYPE 0402LF
J 0
(-5575 1450);
DISPLAY 0.489362 (-5575 1450);
PAINT SKYBLUE (-5575 1450);
FORCEPROP 1 LAST WATTAGE 1/16W
J 2
(-5700 1600);
DISPLAY 0.489362 (-5700 1600);
PAINT SKYBLUE (-5700 1600);
FORCEPROP 1 LAST TOLERANCE 1%
J 0
(-5975 1600);
DISPLAY 0.489362 (-5975 1600);
PAINT SKYBLUE (-5975 1600);
FORCEPROP 1 LAST MATERIAL CHIP
J 0
(-6125 1450);
DISPLAY 0.489362 (-6125 1450);
PAINT SKYBLUE (-6125 1450);
FORCEPROP 1 LAST VALUE 5.6
J 2
(-6025 1600);
DISPLAY 0.489362 (-6025 1600);
PAINT SKYBLUE (-6025 1600);
FORCEPROP 2 LAST CDS_LIB pure_quanta
J 0
(-5975 1525);
DISPLAY INVISIBLE (-5975 1525);
FORCEPROP 1 LAST PATH I40
J 0
(-6025 1675);
DISPLAY 0.978723 (-6025 1675);
PAINT WHITE (-6025 1675);
DISPLAY INVISIBLE (-6025 1675);
FORCEPROP 1 LAST PART_NUMBER CS-5602FB01
J 0
(-5950 1450);
DISPLAY 0.489362 (-5950 1450);
PAINT SKYBLUE (-5950 1450);
DISPLAY INVISIBLE (-5950 1450);
FORCEADD Q_CAP..1
(-5875 1000);
FORCEPROP 1 LAST LOCATION PC190
J 0
(-5825 1100);
DISPLAY 0.489362 (-5825 1100);
PAINT SKYBLUE (-5825 1100);
FORCEPROP 0 LAST $SEC 1
J 0
(-5825 1150);
DISPLAY 0.680851 (-5825 1150);
PAINT MONO (-5825 1150);
DISPLAY INVISIBLE (-5825 1150);
FORCEPROP 0 LAST CDS_SEC 1
J 0
(-5825 1150);
DISPLAY 1.021277 (-5825 1150);
DISPLAY INVISIBLE (-5825 1150);
FORCEPROP 1 LASTPIN (-5875 1100) $PN 1
J 0
(-5865 1080);
DISPLAY 0.489362 (-5865 1080);
PAINT MONO (-5865 1080);
FORCEPROP 1 LASTPIN (-5875 900) $PN 2
J 0
(-5865 880);
DISPLAY 0.489362 (-5865 880);
PAINT MONO (-5865 880);
FORCEPROP 1 LAST VOLTAGE 50V
J 0
(-5825 1000);
DISPLAY 0.489362 (-5825 1000);
PAINT SKYBLUE (-5825 1000);
FORCEPROP 1 LAST PACK_TYPE C0402
J 0
(-5825 800);
DISPLAY 0.489362 (-5825 800);
PAINT SKYBLUE (-5825 800);
FORCEPROP 1 LAST VALUE 560PF
J 0
(-5825 1050);
DISPLAY 0.489362 (-5825 1050);
PAINT SKYBLUE (-5825 1050);
FORCEPROP 1 LAST TOLERANCE 10%
J 0
(-5825 950);
DISPLAY 0.489362 (-5825 950);
PAINT SKYBLUE (-5825 950);
FORCEPROP 1 LAST MATERIAL EMPTY
J 0
(-5825 900);
DISPLAY 0.489362 (-5825 900);
PAINT RED (-5825 900);
FORCEPROP 2 LAST CDS_LIB pure_quanta
J 0
(-5875 1000);
DISPLAY INVISIBLE (-5875 1000);
FORCEPROP 1 LAST PATH I41
J 0
(-5825 1150);
DISPLAY 0.978723 (-5825 1150);
PAINT WHITE (-5825 1150);
DISPLAY INVISIBLE (-5825 1150);
FORCEPROP 1 LAST PART_NUMBER CH1566K1B09
J 0
(-5825 850);
DISPLAY 0.489362 (-5825 850);
PAINT SKYBLUE (-5825 850);
DISPLAY INVISIBLE (-5825 850);
FORCEADD Q_RES..1
(-4925 275);
FORCEPROP 1 LAST LOCATION PR83
J 0
(-4975 325);
DISPLAY 0.489362 (-4975 325);
PAINT SKYBLUE (-4975 325);
FORCEPROP 0 LAST $SEC 1
J 0
(-4675 425);
DISPLAY 0.680851 (-4675 425);
PAINT MONO (-4675 425);
DISPLAY INVISIBLE (-4675 425);
FORCEPROP 0 LAST CDS_SEC 1
J 0
(-4675 425);
DISPLAY 1.021277 (-4675 425);
DISPLAY INVISIBLE (-4675 425);
FORCEPROP 1 LASTPIN (-5025 275) $PN 1
J 0
(-5013 287);
DISPLAY 0.489362 (-5013 287);
PAINT MONO (-5013 287);
FORCEPROP 1 LASTPIN (-4825 275) $PN 2
J 0
(-4863 287);
DISPLAY 0.489362 (-4863 287);
PAINT MONO (-4863 287);
FORCEPROP 1 LAST TOLERANCE 5%
J 0
(-5100 325);
DISPLAY 0.489362 (-5100 325);
PAINT SKYBLUE (-5100 325);
FORCEPROP 1 LAST WATTAGE 1/16W
J 2
(-4675 350);
DISPLAY 0.489362 (-4675 350);
PAINT SKYBLUE (-4675 350);
FORCEPROP 1 LAST MATERIAL CHIP
J 0
(-4775 300);
DISPLAY 0.489362 (-4775 300);
PAINT SKYBLUE (-4775 300);
FORCEPROP 1 LAST VALUE 0
J 2
(-5150 325);
DISPLAY 0.489362 (-5150 325);
PAINT SKYBLUE (-5150 325);
FORCEPROP 1 LAST PACK_TYPE 0402LF
J 0
(-4825 225);
DISPLAY 0.489362 (-4825 225);
PAINT SKYBLUE (-4825 225);
FORCEPROP 2 LAST CDS_LIB pure_quanta
J 0
(-4925 275);
DISPLAY INVISIBLE (-4925 275);
FORCEPROP 1 LAST PATH I42
J 0
(-4975 425);
DISPLAY 0.978723 (-4975 425);
PAINT WHITE (-4975 425);
DISPLAY INVISIBLE (-4975 425);
FORCEPROP 1 LAST PART_NUMBER CS00002JB13
J 0
(-5225 225);
DISPLAY 0.489362 (-5225 225);
PAINT SKYBLUE (-5225 225);
DISPLAY INVISIBLE (-5225 225);
FORCEADD OFFPAGE..6
(-5150 925);
FORCEPROP 2 LAST $XR0 201 
J 0
(-5460 925);
DISPLAY 0.638298 (-5460 925);
PAINT MONO (-5460 925);
FORCEPROP 2 LAST CDS_LIB standard
J 0
(-5150 925);
DISPLAY INVISIBLE (-5150 925);
FORCEPROP 1 LAST OFFPAGE TRUE
J 0
(-4825 800);
DISPLAY 0.872340 (-4825 800);
PAINT GREEN (-4825 800);
DISPLAY INVISIBLE (-4825 800);
FORCEPROP 1 LAST COMMENT_BODY TRUE
J 0
(-5050 850);
DISPLAY 0.872340 (-5050 850);
PAINT GREEN (-5050 850);
DISPLAY INVISIBLE (-5050 850);
FORCEPROP 2 LAST PATH I43
J 0
(-5425 975);
DISPLAY 0.680851 (-5425 975);
DISPLAY INVISIBLE (-5425 975);
FORCEADD Q_CAP..1
(-5175 1400);
FORCEPROP 1 LAST LOCATION PC94
J 0
(-5125 1500);
DISPLAY 0.489362 (-5125 1500);
PAINT SKYBLUE (-5125 1500);
FORCEPROP 0 LAST $SEC 1
J 0
(-5125 1550);
DISPLAY 0.680851 (-5125 1550);
PAINT MONO (-5125 1550);
DISPLAY INVISIBLE (-5125 1550);
FORCEPROP 0 LAST CDS_SEC 1
J 2
(-5125 1525);
DISPLAY 1.021277 (-5125 1525);
DISPLAY INVISIBLE (-5125 1525);
FORCEPROP 1 LASTPIN (-5175 1500) $PN 1
J 0
(-5165 1480);
DISPLAY 0.489362 (-5165 1480);
PAINT MONO (-5165 1480);
FORCEPROP 1 LASTPIN (-5175 1300) $PN 2
J 0
(-5165 1280);
DISPLAY 0.489362 (-5165 1280);
PAINT MONO (-5165 1280);
FORCEPROP 1 LAST VOLTAGE 16V
J 0
(-5125 1400);
DISPLAY 0.489362 (-5125 1400);
PAINT SKYBLUE (-5125 1400);
FORCEPROP 1 LAST TOLERANCE 10%
J 0
(-5125 1350);
DISPLAY 0.489362 (-5125 1350);
PAINT SKYBLUE (-5125 1350);
FORCEPROP 1 LAST PACK_TYPE 0402
J 0
(-5125 1200);
DISPLAY 0.489362 (-5125 1200);
PAINT SKYBLUE (-5125 1200);
FORCEPROP 1 LAST MATERIAL X7R
J 0
(-5125 1300);
DISPLAY 0.489362 (-5125 1300);
PAINT SKYBLUE (-5125 1300);
FORCEPROP 1 LAST VALUE 0.22UF
J 0
(-5125 1450);
DISPLAY 0.489362 (-5125 1450);
PAINT SKYBLUE (-5125 1450);
FORCEPROP 2 LAST CDS_LIB pure_quanta
J 2
(-5175 1400);
DISPLAY INVISIBLE (-5175 1400);
FORCEPROP 1 LAST PATH I44
J 0
(-5125 1550);
DISPLAY 0.978723 (-5125 1550);
PAINT WHITE (-5125 1550);
DISPLAY INVISIBLE (-5125 1550);
FORCEPROP 1 LAST PART_NUMBER CH4223K1B00
J 0
(-5125 1250);
DISPLAY 0.489362 (-5125 1250);
PAINT SKYBLUE (-5125 1250);
DISPLAY INVISIBLE (-5125 1250);
FORCEADD UNIVERSAL_GND..1
(-4825 1700);
FORCEPROP 3 LASTPIN (-4825 1750) SIG_NAME GND\g
J 0
(-4815 1760);
DISPLAY 0.659574 (-4815 1760);
PAINT MONO (-4815 1760);
DISPLAY INVISIBLE (-4815 1760);
FORCEPROP 2 LAST CDS_LIB pure_quanta_power
J 0
(-4825 1700);
PAINT MONO (-4825 1700);
DISPLAY INVISIBLE (-4825 1700);
FORCEPROP 1 LAST HDL_POWER GND
J 1
(-4800 1625);
DISPLAY 0.872340 (-4800 1625);
PAINT GREEN (-4800 1625);
DISPLAY INVISIBLE (-4800 1625);
FORCEPROP 1 LAST PATH I45
J 0
(-4750 1700);
DISPLAY 0.872340 (-4750 1700);
PAINT AQUA (-4750 1700);
DISPLAY INVISIBLE (-4750 1700);
FORCEADD Q_INDUCTOR4P_14..1
(-4150 1050);
FORCEPROP 1 LAST LOCATION PL11
J 0
(-4375 1305);
DISPLAY 0.489362 (-4375 1305);
PAINT SKYBLUE (-4375 1305);
FORCEPROP 0 LAST $SEC 1
J 0
(-4375 1350);
DISPLAY 0.680851 (-4375 1350);
PAINT MONO (-4375 1350);
DISPLAY INVISIBLE (-4375 1350);
FORCEPROP 0 LAST CDS_SEC 1
J 0
(-4375 1350);
DISPLAY 1.021277 (-4375 1350);
DISPLAY INVISIBLE (-4375 1350);
FORCEPROP 0 LASTPIN (-4550 1175) $PN 1
J 2
(-4560 1185);
DISPLAY 0.489362 (-4560 1185);
PAINT MONO (-4560 1185);
FORCEPROP 0 LASTPIN (-4550 925) $PN 2
J 2
(-4560 935);
DISPLAY 0.489362 (-4560 935);
PAINT MONO (-4560 935);
FORCEPROP 0 LASTPIN (-3750 925) $PN 3
J 0
(-3740 935);
DISPLAY 0.489362 (-3740 935);
PAINT MONO (-3740 935);
FORCEPROP 0 LASTPIN (-3750 1175) $PN 4
J 0
(-3740 1185);
DISPLAY 0.489362 (-3740 1185);
PAINT MONO (-3740 1185);
FORCEPROP 2 LAST VALUE 150NH
J 0
(-4250 1225);
DISPLAY 0.489362 (-4250 1225);
PAINT SKYBLUE (-4250 1225);
FORCEPROP 2 LAST PART_TYPE SMLF
J 0
(-4225 800);
DISPLAY 1.021277 (-4225 800);
FORCEPROP 1 LAST MATERIAL IND
J 0
(-4350 1225);
DISPLAY 0.489362 (-4350 1225);
PAINT SKYBLUE (-4350 1225);
FORCEPROP 2 LAST CDS_LIB pure_quanta
J 0
(-4150 1050);
DISPLAY INVISIBLE (-4150 1050);
FORCEPROP 1 LAST NEEDS_NO_SIZE TRUE
J 0
(-4150 1050);
DISPLAY 0.468085 (-4150 1050);
PAINT GREEN (-4150 1050);
DISPLAY INVISIBLE (-4150 1050);
FORCEPROP 1 LAST PATH I46
J 0
(-3950 1205);
DISPLAY 0.723404 (-3950 1205);
PAINT GREEN (-3950 1205);
DISPLAY INVISIBLE (-3950 1205);
FORCEPROP 1 LAST PART_NUMBER CV+15^0TZ04
J 0
(-4100 1225);
DISPLAY 0.489362 (-4100 1225);
PAINT SKYBLUE (-4100 1225);
DISPLAY INVISIBLE (-4100 1225);
FORCEADD Q_CAP..1
(-6000 2075);
FORCEPROP 1 LAST LOCATION PC88_2
J 0
(-5950 2225);
DISPLAY 0.489362 (-5950 2225);
PAINT SKYBLUE (-5950 2225);
FORCEPROP 0 LAST $SEC 1
J 0
(-5950 2275);
DISPLAY 0.680851 (-5950 2275);
PAINT MONO (-5950 2275);
DISPLAY INVISIBLE (-5950 2275);
FORCEPROP 0 LAST CDS_SEC 1
J 0
(-5950 2275);
DISPLAY 1.021277 (-5950 2275);
DISPLAY INVISIBLE (-5950 2275);
FORCEPROP 1 LASTPIN (-6000 2175) $PN 1
J 0
(-5990 2155);
DISPLAY 0.489362 (-5990 2155);
PAINT MONO (-5990 2155);
FORCEPROP 1 LASTPIN (-6000 1975) $PN 2
J 0
(-5990 1955);
DISPLAY 0.489362 (-5990 1955);
PAINT MONO (-5990 1955);
FORCEPROP 1 LAST VALUE 1UF
J 0
(-5950 2175);
DISPLAY 0.489362 (-5950 2175);
PAINT SKYBLUE (-5950 2175);
FORCEPROP 1 LAST VOLTAGE 25V
J 0
(-5950 2125);
DISPLAY 0.489362 (-5950 2125);
PAINT SKYBLUE (-5950 2125);
FORCEPROP 1 LAST TOLERANCE 10%
J 0
(-5950 2075);
DISPLAY 0.489362 (-5950 2075);
PAINT SKYBLUE (-5950 2075);
FORCEPROP 1 LAST MATERIAL X6S
J 0
(-5950 2025);
DISPLAY 0.489362 (-5950 2025);
PAINT SKYBLUE (-5950 2025);
FORCEPROP 1 LAST PACK_TYPE C0402
J 0
(-5950 1975);
DISPLAY 0.489362 (-5950 1975);
PAINT SKYBLUE (-5950 1975);
FORCEPROP 2 LAST CDS_LIB pure_quanta
J 0
(-6000 2075);
DISPLAY INVISIBLE (-6000 2075);
FORCEPROP 1 LAST PATH I47
J 0
(-5950 2225);
DISPLAY 0.978723 (-5950 2225);
PAINT WHITE (-5950 2225);
DISPLAY INVISIBLE (-5950 2225);
FORCEPROP 1 LAST PART_NUMBER CH5104KEB02
J 0
(-5950 1925);
DISPLAY 0.489362 (-5950 1925);
PAINT SKYBLUE (-5950 1925);
DISPLAY INVISIBLE (-5950 1925);
FORCEADD Q_CAP..1
(-5600 2075);
FORCEPROP 1 LAST LOCATION PC90_2
J 0
(-5550 2225);
DISPLAY 0.489362 (-5550 2225);
PAINT SKYBLUE (-5550 2225);
FORCEPROP 0 LAST $SEC 1
J 0
(-5550 2275);
DISPLAY 0.680851 (-5550 2275);
PAINT MONO (-5550 2275);
DISPLAY INVISIBLE (-5550 2275);
FORCEPROP 0 LAST CDS_SEC 1
J 0
(-5550 2275);
DISPLAY 1.021277 (-5550 2275);
DISPLAY INVISIBLE (-5550 2275);
FORCEPROP 1 LASTPIN (-5600 2175) $PN 1
J 0
(-5590 2155);
DISPLAY 0.489362 (-5590 2155);
PAINT MONO (-5590 2155);
FORCEPROP 1 LASTPIN (-5600 1975) $PN 2
J 0
(-5590 1955);
DISPLAY 0.489362 (-5590 1955);
PAINT MONO (-5590 1955);
FORCEPROP 1 LAST TOLERANCE 20%
J 0
(-5550 2075);
DISPLAY 0.489362 (-5550 2075);
PAINT SKYBLUE (-5550 2075);
FORCEPROP 1 LAST VOLTAGE 16V
J 0
(-5550 2125);
DISPLAY 0.489362 (-5550 2125);
PAINT SKYBLUE (-5550 2125);
FORCEPROP 1 LAST VALUE 22UF
J 0
(-5550 2175);
DISPLAY 0.489362 (-5550 2175);
PAINT SKYBLUE (-5550 2175);
FORCEPROP 1 LAST MATERIAL X6S
J 0
(-5550 2025);
DISPLAY 0.489362 (-5550 2025);
PAINT SKYBLUE (-5550 2025);
FORCEPROP 1 LAST PACK_TYPE C0805
J 0
(-5550 1975);
DISPLAY 0.489362 (-5550 1975);
PAINT SKYBLUE (-5550 1975);
FORCEPROP 2 LAST CDS_LIB pure_quanta
J 0
(-5600 2075);
DISPLAY INVISIBLE (-5600 2075);
FORCEPROP 1 LAST PATH I48
J 0
(-5550 2225);
DISPLAY 0.978723 (-5550 2225);
PAINT WHITE (-5550 2225);
DISPLAY INVISIBLE (-5550 2225);
FORCEPROP 1 LAST PART_NUMBER CH6223MEA01
J 0
(-5550 1925);
DISPLAY 0.489362 (-5550 1925);
PAINT SKYBLUE (-5550 1925);
DISPLAY INVISIBLE (-5550 1925);
FORCEADD UNIVERSAL_GND..1
(-5875 3275);
FORCEPROP 3 LASTPIN (-5875 3325) SIG_NAME GND\g
J 0
(-5865 3335);
DISPLAY 0.659574 (-5865 3335);
PAINT MONO (-5865 3335);
DISPLAY INVISIBLE (-5865 3335);
FORCEPROP 2 LAST CDS_LIB pure_quanta_power
J 0
(-5875 3275);
DISPLAY INVISIBLE (-5875 3275);
FORCEPROP 1 LAST HDL_POWER GND
J 1
(-5850 3200);
DISPLAY 0.872340 (-5850 3200);
PAINT GREEN (-5850 3200);
DISPLAY INVISIBLE (-5850 3200);
FORCEPROP 1 LAST PATH I49
J 0
(-5800 3275);
DISPLAY 0.872340 (-5800 3275);
PAINT AQUA (-5800 3275);
DISPLAY INVISIBLE (-5800 3275);
FORCEADD OFFPAGE..5
(-8600 675);
FORCEPROP 2 LAST $XR3 200 
J 0
(-8975 639);
DISPLAY 0.638298 (-8975 639);
PAINT MONO (-8975 639);
FORCEPROP 2 LAST $XR2 203 
J 0
(-8855 639);
DISPLAY 0.638298 (-8855 639);
PAINT MONO (-8855 639);
FORCEPROP 2 LAST $XR1 202 
J 0
(-8975 675);
DISPLAY 0.638298 (-8975 675);
PAINT MONO (-8975 675);
FORCEPROP 2 LAST $XR0 201 
J 0
(-8855 675);
DISPLAY 0.638298 (-8855 675);
PAINT MONO (-8855 675);
FORCEPROP 2 LAST CDS_LIB standard
J 0
(-8600 675);
DISPLAY INVISIBLE (-8600 675);
FORCEPROP 1 LAST OFFPAGE TRUE
J 0
(-8275 550);
DISPLAY 0.872340 (-8275 550);
PAINT GREEN (-8275 550);
DISPLAY INVISIBLE (-8275 550);
FORCEPROP 1 LAST COMMENT_BODY TRUE
J 0
(-8500 600);
DISPLAY 0.872340 (-8500 600);
PAINT GREEN (-8500 600);
DISPLAY INVISIBLE (-8500 600);
FORCEPROP 2 LAST PATH I5
J 0
(-8875 725);
DISPLAY 0.680851 (-8875 725);
DISPLAY INVISIBLE (-8875 725);
FORCEADD Q_RES..2
(-5875 3500);
FORCEPROP 1 LAST LOCATION PR506
J 0
(-5830 3625);
DISPLAY 0.489362 (-5830 3625);
PAINT SKYBLUE (-5830 3625);
FORCEPROP 0 LAST $SEC 1
J 0
(-5825 3675);
DISPLAY 0.680851 (-5825 3675);
PAINT MONO (-5825 3675);
DISPLAY INVISIBLE (-5825 3675);
FORCEPROP 0 LAST CDS_SEC 1
J 0
(-5825 3675);
DISPLAY 1.021277 (-5825 3675);
DISPLAY INVISIBLE (-5825 3675);
FORCEPROP 1 LASTPIN (-5875 3600) $PN 1
J 0
(-5870 3562);
DISPLAY 0.489362 (-5870 3562);
PAINT MONO (-5870 3562);
FORCEPROP 1 LASTPIN (-5875 3400) $PN 2
J 0
(-5870 3410);
DISPLAY 0.489362 (-5870 3410);
PAINT MONO (-5870 3410);
FORCEPROP 1 LAST PACK_TYPE 0402LF
J 0
(-5835 3325);
DISPLAY 0.489362 (-5835 3325);
PAINT SKYBLUE (-5835 3325);
FORCEPROP 1 LAST VALUE 1.5
J 0
(-5830 3575);
DISPLAY 0.489362 (-5830 3575);
PAINT SKYBLUE (-5830 3575);
FORCEPROP 1 LAST TOLERANCE 1%
J 0
(-5830 3525);
DISPLAY 0.489362 (-5830 3525);
PAINT SKYBLUE (-5830 3525);
FORCEPROP 1 LAST WATTAGE 1/8W
J 0
(-5835 3475);
DISPLAY 0.489362 (-5835 3475);
PAINT SKYBLUE (-5835 3475);
FORCEPROP 1 LAST MATERIAL EMPTY
J 0
(-5835 3425);
DISPLAY 0.489362 (-5835 3425);
PAINT RED (-5835 3425);
FORCEPROP 2 LAST CDS_LIB pure_quanta
J 0
(-5875 3500);
DISPLAY INVISIBLE (-5875 3500);
FORCEPROP 1 LAST PATH I50
J 0
(-5825 3675);
DISPLAY 0.978723 (-5825 3675);
PAINT WHITE (-5825 3675);
DISPLAY INVISIBLE (-5825 3675);
FORCEPROP 1 LAST PART_NUMBER CS-1504FB00
J 0
(-5835 3375);
DISPLAY 0.489362 (-5835 3375);
PAINT SKYBLUE (-5835 3375);
DISPLAY INVISIBLE (-5835 3375);
FORCEADD Q_CAP..1
(-5200 2075);
FORCEPROP 1 LAST LOCATION PC93_2
J 0
(-5150 2225);
DISPLAY 0.489362 (-5150 2225);
PAINT SKYBLUE (-5150 2225);
FORCEPROP 0 LAST $SEC 1
J 0
(-5150 2275);
DISPLAY 0.680851 (-5150 2275);
PAINT MONO (-5150 2275);
DISPLAY INVISIBLE (-5150 2275);
FORCEPROP 0 LAST CDS_SEC 1
J 0
(-5150 2275);
DISPLAY 1.021277 (-5150 2275);
DISPLAY INVISIBLE (-5150 2275);
FORCEPROP 1 LASTPIN (-5200 2175) $PN 1
J 0
(-5190 2155);
DISPLAY 0.489362 (-5190 2155);
PAINT MONO (-5190 2155);
FORCEPROP 1 LASTPIN (-5200 1975) $PN 2
J 0
(-5190 1955);
DISPLAY 0.489362 (-5190 1955);
PAINT MONO (-5190 1955);
FORCEPROP 1 LAST TOLERANCE 20%
J 0
(-5150 2075);
DISPLAY 0.489362 (-5150 2075);
PAINT SKYBLUE (-5150 2075);
FORCEPROP 1 LAST VOLTAGE 16V
J 0
(-5150 2125);
DISPLAY 0.489362 (-5150 2125);
PAINT SKYBLUE (-5150 2125);
FORCEPROP 1 LAST VALUE 22UF
J 0
(-5150 2175);
DISPLAY 0.489362 (-5150 2175);
PAINT SKYBLUE (-5150 2175);
FORCEPROP 1 LAST PACK_TYPE C0805
J 0
(-5150 1975);
DISPLAY 0.489362 (-5150 1975);
PAINT SKYBLUE (-5150 1975);
FORCEPROP 1 LAST MATERIAL X6S
J 0
(-5150 2025);
DISPLAY 0.489362 (-5150 2025);
PAINT SKYBLUE (-5150 2025);
FORCEPROP 2 LAST CDS_LIB pure_quanta
J 0
(-5200 2075);
DISPLAY INVISIBLE (-5200 2075);
FORCEPROP 1 LAST PATH I51
J 0
(-5150 2225);
DISPLAY 0.978723 (-5150 2225);
PAINT WHITE (-5150 2225);
DISPLAY INVISIBLE (-5150 2225);
FORCEPROP 1 LAST PART_NUMBER CH6223MEA01
J 0
(-5150 1925);
DISPLAY 0.489362 (-5150 1925);
PAINT SKYBLUE (-5150 1925);
DISPLAY INVISIBLE (-5150 1925);
FORCEADD Q_CAP..1
(-4825 2075);
FORCEPROP 1 LAST LOCATION PC96_2
J 0
(-4775 2225);
DISPLAY 0.489362 (-4775 2225);
PAINT SKYBLUE (-4775 2225);
FORCEPROP 0 LAST $SEC 1
J 0
(-4775 2275);
DISPLAY 0.680851 (-4775 2275);
PAINT MONO (-4775 2275);
DISPLAY INVISIBLE (-4775 2275);
FORCEPROP 0 LAST CDS_SEC 1
J 0
(-4775 2275);
DISPLAY 1.021277 (-4775 2275);
DISPLAY INVISIBLE (-4775 2275);
FORCEPROP 1 LASTPIN (-4825 2175) $PN 1
J 0
(-4815 2155);
DISPLAY 0.489362 (-4815 2155);
PAINT MONO (-4815 2155);
FORCEPROP 1 LASTPIN (-4825 1975) $PN 2
J 0
(-4815 1955);
DISPLAY 0.489362 (-4815 1955);
PAINT MONO (-4815 1955);
FORCEPROP 1 LAST TOLERANCE 20%
J 0
(-4775 2075);
DISPLAY 0.489362 (-4775 2075);
PAINT SKYBLUE (-4775 2075);
FORCEPROP 1 LAST VOLTAGE 16V
J 0
(-4775 2125);
DISPLAY 0.489362 (-4775 2125);
PAINT SKYBLUE (-4775 2125);
FORCEPROP 1 LAST VALUE 22UF
J 0
(-4775 2175);
DISPLAY 0.489362 (-4775 2175);
PAINT SKYBLUE (-4775 2175);
FORCEPROP 1 LAST MATERIAL X6S
J 0
(-4775 2025);
DISPLAY 0.489362 (-4775 2025);
PAINT SKYBLUE (-4775 2025);
FORCEPROP 1 LAST PACK_TYPE C0805
J 0
(-4775 1975);
DISPLAY 0.489362 (-4775 1975);
PAINT SKYBLUE (-4775 1975);
FORCEPROP 2 LAST CDS_LIB pure_quanta
J 0
(-4825 2075);
DISPLAY INVISIBLE (-4825 2075);
FORCEPROP 1 LAST PATH I52
J 0
(-4775 2225);
DISPLAY 0.978723 (-4775 2225);
PAINT WHITE (-4775 2225);
DISPLAY INVISIBLE (-4775 2225);
FORCEPROP 1 LAST PART_NUMBER CH6223MEA01
J 0
(-4775 1925);
DISPLAY 0.489362 (-4775 1925);
PAINT SKYBLUE (-4775 1925);
DISPLAY INVISIBLE (-4775 1925);
FORCEADD VCC_CORE..1
(-4825 2425);
FORCEPROP 3 LASTPIN (-4825 2375) SIG_NAME SW_P12V_AUX_PVDDCR_CPU1_P0_FLT\g
J 0
(-4815 2385);
DISPLAY 0.659574 (-4815 2385);
PAINT MONO (-4815 2385);
DISPLAY INVISIBLE (-4815 2385);
FORCEPROP 1 LAST HDL_POWER SW_P12V_AUX_PVDDCR_CPU1_P0_FLT
J 1
(-4825 2475);
DISPLAY 0.489362 (-4825 2475);
PAINT GREEN (-4825 2475);
FORCEPROP 2 LAST CDS_LIB pure_quanta_power
J 0
(-4825 2425);
DISPLAY INVISIBLE (-4825 2425);
FORCEPROP 1 LAST PATH I53
J 0
(-4775 2450);
DISPLAY 0.872340 (-4775 2450);
PAINT AQUA (-4775 2450);
DISPLAY INVISIBLE (-4775 2450);
FORCEADD Q_RES..1
(-4850 3225);
FORCEPROP 1 LAST LOCATION PR84
J 0
(-4875 3275);
DISPLAY 0.489362 (-4875 3275);
PAINT SKYBLUE (-4875 3275);
FORCEPROP 0 LAST $SEC 1
J 0
(-4600 3375);
DISPLAY 0.680851 (-4600 3375);
PAINT MONO (-4600 3375);
DISPLAY INVISIBLE (-4600 3375);
FORCEPROP 0 LAST CDS_SEC 1
J 0
(-4600 3375);
DISPLAY 1.021277 (-4600 3375);
DISPLAY INVISIBLE (-4600 3375);
FORCEPROP 1 LASTPIN (-4950 3225) $PN 1
J 0
(-4938 3237);
DISPLAY 0.489362 (-4938 3237);
PAINT MONO (-4938 3237);
FORCEPROP 1 LASTPIN (-4750 3225) $PN 2
J 0
(-4788 3237);
DISPLAY 0.489362 (-4788 3237);
PAINT MONO (-4788 3237);
FORCEPROP 1 LAST MATERIAL CHIP
J 0
(-4700 3250);
DISPLAY 0.489362 (-4700 3250);
PAINT SKYBLUE (-4700 3250);
FORCEPROP 1 LAST PACK_TYPE 0402LF
J 0
(-4750 3175);
DISPLAY 0.489362 (-4750 3175);
PAINT SKYBLUE (-4750 3175);
FORCEPROP 1 LAST TOLERANCE 5%
J 0
(-5000 3275);
DISPLAY 0.489362 (-5000 3275);
PAINT SKYBLUE (-5000 3275);
FORCEPROP 1 LAST WATTAGE 1/16W
J 2
(-4600 3300);
DISPLAY 0.489362 (-4600 3300);
PAINT SKYBLUE (-4600 3300);
FORCEPROP 1 LAST VALUE 0
J 2
(-5025 3275);
DISPLAY 0.489362 (-5025 3275);
PAINT SKYBLUE (-5025 3275);
FORCEPROP 2 LAST CDS_LIB pure_quanta
J 0
(-4850 3225);
DISPLAY INVISIBLE (-4850 3225);
FORCEPROP 1 LAST PATH I54
J 0
(-4900 3375);
DISPLAY 0.978723 (-4900 3375);
PAINT WHITE (-4900 3375);
DISPLAY INVISIBLE (-4900 3375);
FORCEPROP 1 LAST PART_NUMBER CS00002JB13
J 0
(-5125 3175);
DISPLAY 0.489362 (-5125 3175);
PAINT SKYBLUE (-5125 3175);
DISPLAY INVISIBLE (-5125 3175);
FORCEADD Q_CAP..1
(-6425 5025);
FORCEPROP 1 LAST LOCATION PC85_1
J 0
(-6375 5175);
DISPLAY 0.489362 (-6375 5175);
PAINT SKYBLUE (-6375 5175);
FORCEPROP 0 LAST $SEC 1
J 0
(-6375 5175);
DISPLAY 0.680851 (-6375 5175);
PAINT MONO (-6375 5175);
DISPLAY INVISIBLE (-6375 5175);
FORCEPROP 0 LAST CDS_SEC 1
J 0
(-6375 5175);
DISPLAY 1.021277 (-6375 5175);
DISPLAY INVISIBLE (-6375 5175);
FORCEPROP 1 LASTPIN (-6425 5125) $PN 1
J 0
(-6415 5105);
DISPLAY 0.489362 (-6415 5105);
PAINT MONO (-6415 5105);
FORCEPROP 1 LASTPIN (-6425 4925) $PN 2
J 0
(-6415 4905);
DISPLAY 0.489362 (-6415 4905);
PAINT MONO (-6415 4905);
FORCEPROP 1 LAST MATERIAL X7R
J 0
(-6375 4975);
DISPLAY 0.489362 (-6375 4975);
PAINT SKYBLUE (-6375 4975);
FORCEPROP 1 LAST VALUE 0.1UF
J 0
(-6375 5125);
DISPLAY 0.489362 (-6375 5125);
PAINT SKYBLUE (-6375 5125);
FORCEPROP 1 LAST VOLTAGE 25V
J 0
(-6375 5075);
DISPLAY 0.489362 (-6375 5075);
PAINT SKYBLUE (-6375 5075);
FORCEPROP 1 LAST PACK_TYPE 0402
J 0
(-6375 4925);
DISPLAY 0.489362 (-6375 4925);
PAINT SKYBLUE (-6375 4925);
FORCEPROP 1 LAST TOLERANCE 10%
J 0
(-6375 5025);
DISPLAY 0.489362 (-6375 5025);
PAINT SKYBLUE (-6375 5025);
FORCEPROP 2 LAST CDS_LIB pure_quanta
J 0
(-6425 5025);
DISPLAY INVISIBLE (-6425 5025);
FORCEPROP 1 LAST PATH I55
J 0
(-6375 5175);
DISPLAY 0.978723 (-6375 5175);
PAINT WHITE (-6375 5175);
DISPLAY INVISIBLE (-6375 5175);
FORCEPROP 1 LAST PART_NUMBER CH4104K1B00
J 0
(-6375 4875);
DISPLAY 0.489362 (-6375 4875);
PAINT SKYBLUE (-6375 4875);
DISPLAY INVISIBLE (-6375 4875);
FORCEADD Q_RES..1
(-5950 4475);
FORCEPROP 1 LAST LOCATION PR82
J 0
(-5975 4525);
DISPLAY 0.489362 (-5975 4525);
PAINT SKYBLUE (-5975 4525);
FORCEPROP 0 LAST $SEC 1
J 0
(-6075 4625);
DISPLAY 0.680851 (-6075 4625);
PAINT MONO (-6075 4625);
DISPLAY INVISIBLE (-6075 4625);
FORCEPROP 0 LAST CDS_SEC 1
J 0
(-6075 4625);
DISPLAY 1.021277 (-6075 4625);
DISPLAY INVISIBLE (-6075 4625);
FORCEPROP 1 LASTPIN (-6050 4475) $PN 1
J 0
(-6038 4487);
DISPLAY 0.787234 (-6038 4487);
PAINT MONO (-6038 4487);
DISPLAY INVISIBLE (-6038 4487);
FORCEPROP 1 LASTPIN (-5850 4475) $PN 2
J 0
(-5888 4487);
DISPLAY 0.787234 (-5888 4487);
PAINT MONO (-5888 4487);
DISPLAY INVISIBLE (-5888 4487);
FORCEPROP 1 LAST MATERIAL CHIP
J 0
(-5825 4350);
DISPLAY 0.489362 (-5825 4350);
PAINT SKYBLUE (-5825 4350);
FORCEPROP 1 LAST TOLERANCE 1%
J 0
(-6075 4500);
DISPLAY 0.489362 (-6075 4500);
PAINT SKYBLUE (-6075 4500);
FORCEPROP 1 LAST WATTAGE 1/16W
J 2
(-5675 4550);
DISPLAY 0.489362 (-5675 4550);
PAINT SKYBLUE (-5675 4550);
FORCEPROP 1 LAST VALUE 5.6
J 2
(-6025 4550);
DISPLAY 0.489362 (-6025 4550);
PAINT SKYBLUE (-6025 4550);
FORCEPROP 1 LAST PACK_TYPE 0402LF
J 0
(-5850 4400);
DISPLAY 0.489362 (-5850 4400);
PAINT SKYBLUE (-5850 4400);
FORCEPROP 2 LAST CDS_LIB pure_quanta
J 0
(-5950 4475);
DISPLAY INVISIBLE (-5950 4475);
FORCEPROP 1 LAST PATH I56
J 0
(-6000 4625);
DISPLAY 0.978723 (-6000 4625);
PAINT WHITE (-6000 4625);
DISPLAY INVISIBLE (-6000 4625);
FORCEPROP 1 LAST PART_NUMBER CS-5602FB01
J 0
(-6250 4400);
DISPLAY 0.489362 (-6250 4400);
PAINT SKYBLUE (-6250 4400);
DISPLAY INVISIBLE (-6250 4400);
FORCEADD Q_CAP..1
(-5875 3950);
FORCEPROP 1 LAST LOCATION PC189
J 0
(-5825 4050);
DISPLAY 0.489362 (-5825 4050);
PAINT SKYBLUE (-5825 4050);
FORCEPROP 0 LAST $SEC 1
J 0
(-5825 4100);
DISPLAY 0.680851 (-5825 4100);
PAINT MONO (-5825 4100);
DISPLAY INVISIBLE (-5825 4100);
FORCEPROP 0 LAST CDS_SEC 1
J 0
(-5825 4100);
DISPLAY 1.021277 (-5825 4100);
DISPLAY INVISIBLE (-5825 4100);
FORCEPROP 1 LASTPIN (-5875 4050) $PN 1
J 0
(-5865 4030);
DISPLAY 0.489362 (-5865 4030);
PAINT MONO (-5865 4030);
FORCEPROP 1 LASTPIN (-5875 3850) $PN 2
J 0
(-5865 3830);
DISPLAY 0.489362 (-5865 3830);
PAINT MONO (-5865 3830);
FORCEPROP 1 LAST PACK_TYPE C0402
J 0
(-5825 3750);
DISPLAY 0.489362 (-5825 3750);
PAINT SKYBLUE (-5825 3750);
FORCEPROP 1 LAST VOLTAGE 50V
J 0
(-5825 3950);
DISPLAY 0.489362 (-5825 3950);
PAINT SKYBLUE (-5825 3950);
FORCEPROP 1 LAST VALUE 560PF
J 0
(-5825 4000);
DISPLAY 0.489362 (-5825 4000);
PAINT SKYBLUE (-5825 4000);
FORCEPROP 1 LAST TOLERANCE 10%
J 0
(-5825 3900);
DISPLAY 0.489362 (-5825 3900);
PAINT SKYBLUE (-5825 3900);
FORCEPROP 1 LAST MATERIAL EMPTY
J 0
(-5825 3850);
DISPLAY 0.489362 (-5825 3850);
PAINT RED (-5825 3850);
FORCEPROP 2 LAST CDS_LIB pure_quanta
J 0
(-5875 3950);
DISPLAY INVISIBLE (-5875 3950);
FORCEPROP 1 LAST PATH I57
J 0
(-5825 4100);
DISPLAY 0.978723 (-5825 4100);
PAINT WHITE (-5825 4100);
DISPLAY INVISIBLE (-5825 4100);
FORCEPROP 1 LAST PART_NUMBER CH1566K1B09
J 0
(-5825 3800);
DISPLAY 0.489362 (-5825 3800);
PAINT SKYBLUE (-5825 3800);
DISPLAY INVISIBLE (-5825 3800);
FORCEADD OFFPAGE..3
R 2
(-5375 3875);
FORCEPROP 2 LAST $XR0 203 
J 0
(-5685 3875);
DISPLAY 0.638298 (-5685 3875);
PAINT MONO (-5685 3875);
FORCEPROP 2 LAST CDS_LIB standard
J 2
(-5375 3875);
DISPLAY INVISIBLE (-5375 3875);
FORCEPROP 1 LAST OFFPAGE TRUE
J 2
(-5700 3750);
DISPLAY 0.872340 (-5700 3750);
PAINT GREEN (-5700 3750);
DISPLAY INVISIBLE (-5700 3750);
FORCEPROP 1 LAST COMMENT_BODY TRUE
J 2
(-5325 3775);
DISPLAY 0.872340 (-5325 3775);
PAINT GREEN (-5325 3775);
DISPLAY INVISIBLE (-5325 3775);
FORCEPROP 2 LAST PATH I58
J 0
(-5650 3925);
DISPLAY 0.680851 (-5650 3925);
DISPLAY INVISIBLE (-5650 3925);
FORCEADD Q_CAP..1
(-6025 5025);
FORCEPROP 1 LAST LOCATION PC87_1
J 0
(-5975 5175);
DISPLAY 0.489362 (-5975 5175);
PAINT SKYBLUE (-5975 5175);
FORCEPROP 0 LAST $SEC 1
J 0
(-5975 5225);
DISPLAY 0.680851 (-5975 5225);
PAINT MONO (-5975 5225);
DISPLAY INVISIBLE (-5975 5225);
FORCEPROP 0 LAST CDS_SEC 1
J 0
(-5975 5225);
DISPLAY 1.021277 (-5975 5225);
DISPLAY INVISIBLE (-5975 5225);
FORCEPROP 1 LASTPIN (-6025 5125) $PN 1
J 0
(-6015 5105);
DISPLAY 0.489362 (-6015 5105);
PAINT MONO (-6015 5105);
FORCEPROP 1 LASTPIN (-6025 4925) $PN 2
J 0
(-6015 4905);
DISPLAY 0.489362 (-6015 4905);
PAINT MONO (-6015 4905);
FORCEPROP 1 LAST PACK_TYPE C0402
J 0
(-5975 4925);
DISPLAY 0.489362 (-5975 4925);
PAINT SKYBLUE (-5975 4925);
FORCEPROP 1 LAST VALUE 1UF
J 0
(-5975 5125);
DISPLAY 0.489362 (-5975 5125);
PAINT SKYBLUE (-5975 5125);
FORCEPROP 1 LAST VOLTAGE 25V
J 0
(-5975 5075);
DISPLAY 0.489362 (-5975 5075);
PAINT SKYBLUE (-5975 5075);
FORCEPROP 1 LAST MATERIAL X6S
J 0
(-5975 4975);
DISPLAY 0.489362 (-5975 4975);
PAINT SKYBLUE (-5975 4975);
FORCEPROP 1 LAST TOLERANCE 10%
J 0
(-5975 5025);
DISPLAY 0.489362 (-5975 5025);
PAINT SKYBLUE (-5975 5025);
FORCEPROP 2 LAST CDS_LIB pure_quanta
J 0
(-6025 5025);
DISPLAY INVISIBLE (-6025 5025);
FORCEPROP 1 LAST PATH I59
J 0
(-5975 5175);
DISPLAY 0.978723 (-5975 5175);
PAINT WHITE (-5975 5175);
DISPLAY INVISIBLE (-5975 5175);
FORCEPROP 1 LAST PART_NUMBER CH5104KEB02
J 0
(-5975 4875);
DISPLAY 0.489362 (-5975 4875);
PAINT SKYBLUE (-5975 4875);
DISPLAY INVISIBLE (-5975 4875);
FORCEADD OFFPAGE..1
(-8600 575);
FORCEPROP 2 LAST $XR0 200 
J 0
(-8852 575);
DISPLAY 0.638298 (-8852 575);
PAINT MONO (-8852 575);
FORCEPROP 2 LAST CDS_LIB standard
J 0
(-8600 575);
DISPLAY INVISIBLE (-8600 575);
FORCEPROP 1 LAST OFFPAGE TRUE
J 0
(-8275 450);
DISPLAY 0.872340 (-8275 450);
PAINT GREEN (-8275 450);
DISPLAY INVISIBLE (-8275 450);
FORCEPROP 1 LAST COMMENT_BODY TRUE
J 0
(-8475 475);
DISPLAY 0.872340 (-8475 475);
PAINT GREEN (-8475 475);
DISPLAY INVISIBLE (-8475 475);
FORCEPROP 2 LAST PATH I6
J 0
(-8850 625);
DISPLAY 0.680851 (-8850 625);
DISPLAY INVISIBLE (-8850 625);
FORCEADD Q_CAP..1
(-5625 5025);
FORCEPROP 1 LAST LOCATION PC89_1
J 0
(-5575 5175);
DISPLAY 0.489362 (-5575 5175);
PAINT SKYBLUE (-5575 5175);
FORCEPROP 0 LAST $SEC 1
J 0
(-5575 5225);
DISPLAY 0.680851 (-5575 5225);
PAINT MONO (-5575 5225);
DISPLAY INVISIBLE (-5575 5225);
FORCEPROP 0 LAST CDS_SEC 1
J 0
(-5575 5225);
DISPLAY 1.021277 (-5575 5225);
DISPLAY INVISIBLE (-5575 5225);
FORCEPROP 1 LASTPIN (-5625 5125) $PN 1
J 0
(-5615 5105);
DISPLAY 0.489362 (-5615 5105);
PAINT MONO (-5615 5105);
FORCEPROP 1 LASTPIN (-5625 4925) $PN 2
J 0
(-5615 4905);
DISPLAY 0.489362 (-5615 4905);
PAINT MONO (-5615 4905);
FORCEPROP 1 LAST MATERIAL X6S
J 0
(-5575 4975);
DISPLAY 0.489362 (-5575 4975);
PAINT SKYBLUE (-5575 4975);
FORCEPROP 1 LAST TOLERANCE 20%
J 0
(-5575 5025);
DISPLAY 0.489362 (-5575 5025);
PAINT SKYBLUE (-5575 5025);
FORCEPROP 1 LAST VOLTAGE 16V
J 0
(-5575 5075);
DISPLAY 0.489362 (-5575 5075);
PAINT SKYBLUE (-5575 5075);
FORCEPROP 1 LAST VALUE 22UF
J 0
(-5575 5125);
DISPLAY 0.489362 (-5575 5125);
PAINT SKYBLUE (-5575 5125);
FORCEPROP 1 LAST PACK_TYPE C0805
J 0
(-5575 4925);
DISPLAY 0.489362 (-5575 4925);
PAINT SKYBLUE (-5575 4925);
FORCEPROP 2 LAST CDS_LIB pure_quanta
J 0
(-5625 5025);
DISPLAY INVISIBLE (-5625 5025);
FORCEPROP 1 LAST PATH I60
J 0
(-5575 5175);
DISPLAY 0.978723 (-5575 5175);
PAINT WHITE (-5575 5175);
DISPLAY INVISIBLE (-5575 5175);
FORCEPROP 1 LAST PART_NUMBER CH6223MEA01
J 0
(-5575 4875);
DISPLAY 0.489362 (-5575 4875);
PAINT SKYBLUE (-5575 4875);
DISPLAY INVISIBLE (-5575 4875);
FORCEADD Q_CAP..1
(-5225 4350);
FORCEPROP 1 LAST LOCATION PC92
J 0
(-5175 4450);
DISPLAY 0.489362 (-5175 4450);
PAINT SKYBLUE (-5175 4450);
FORCEPROP 0 LAST $SEC 1
J 0
(-5175 4500);
DISPLAY 0.680851 (-5175 4500);
PAINT MONO (-5175 4500);
DISPLAY INVISIBLE (-5175 4500);
FORCEPROP 0 LAST CDS_SEC 1
J 0
(-5175 4500);
DISPLAY 1.021277 (-5175 4500);
DISPLAY INVISIBLE (-5175 4500);
FORCEPROP 1 LASTPIN (-5225 4450) $PN 1
J 0
(-5215 4430);
DISPLAY 0.489362 (-5215 4430);
PAINT MONO (-5215 4430);
FORCEPROP 1 LASTPIN (-5225 4250) $PN 2
J 0
(-5215 4230);
DISPLAY 0.489362 (-5215 4230);
PAINT MONO (-5215 4230);
FORCEPROP 1 LAST PACK_TYPE 0402
J 0
(-5175 4150);
DISPLAY 0.489362 (-5175 4150);
PAINT SKYBLUE (-5175 4150);
FORCEPROP 1 LAST VOLTAGE 16V
J 0
(-5175 4350);
DISPLAY 0.489362 (-5175 4350);
PAINT SKYBLUE (-5175 4350);
FORCEPROP 1 LAST MATERIAL X7R
J 0
(-5175 4250);
DISPLAY 0.489362 (-5175 4250);
PAINT SKYBLUE (-5175 4250);
FORCEPROP 1 LAST TOLERANCE 10%
J 0
(-5175 4300);
DISPLAY 0.489362 (-5175 4300);
PAINT SKYBLUE (-5175 4300);
FORCEPROP 1 LAST VALUE 0.22UF
J 0
(-5175 4400);
DISPLAY 0.489362 (-5175 4400);
PAINT SKYBLUE (-5175 4400);
FORCEPROP 2 LAST CDS_LIB pure_quanta
J 2
(-5225 4350);
DISPLAY INVISIBLE (-5225 4350);
FORCEPROP 1 LAST PATH I61
J 0
(-5175 4500);
DISPLAY 0.978723 (-5175 4500);
PAINT WHITE (-5175 4500);
DISPLAY INVISIBLE (-5175 4500);
FORCEPROP 1 LAST PART_NUMBER CH4223K1B00
J 0
(-5175 4200);
DISPLAY 0.489362 (-5175 4200);
PAINT SKYBLUE (-5175 4200);
DISPLAY INVISIBLE (-5175 4200);
FORCEADD Q_INDUCTOR4P_14..1
(-4450 4000);
FORCEPROP 1 LAST LOCATION PL10
J 0
(-4675 4255);
DISPLAY 0.489362 (-4675 4255);
PAINT SKYBLUE (-4675 4255);
FORCEPROP 0 LAST $SEC 1
J 0
(-4675 4300);
DISPLAY 0.680851 (-4675 4300);
PAINT MONO (-4675 4300);
DISPLAY INVISIBLE (-4675 4300);
FORCEPROP 0 LAST CDS_SEC 1
J 0
(-4675 4300);
DISPLAY 1.021277 (-4675 4300);
DISPLAY INVISIBLE (-4675 4300);
FORCEPROP 0 LASTPIN (-4850 4125) $PN 1
J 2
(-4860 4135);
DISPLAY 0.489362 (-4860 4135);
PAINT MONO (-4860 4135);
FORCEPROP 0 LASTPIN (-4850 3875) $PN 2
J 2
(-4860 3885);
DISPLAY 0.489362 (-4860 3885);
PAINT MONO (-4860 3885);
FORCEPROP 0 LASTPIN (-4050 3875) $PN 3
J 0
(-4040 3885);
DISPLAY 0.489362 (-4040 3885);
PAINT MONO (-4040 3885);
FORCEPROP 0 LASTPIN (-4050 4125) $PN 4
J 0
(-4040 4135);
DISPLAY 0.489362 (-4040 4135);
PAINT MONO (-4040 4135);
FORCEPROP 1 LAST MATERIAL IND
J 0
(-4650 4175);
DISPLAY 0.489362 (-4650 4175);
PAINT SKYBLUE (-4650 4175);
FORCEPROP 2 LAST VALUE 150NH
J 0
(-4550 4175);
DISPLAY 0.489362 (-4550 4175);
PAINT SKYBLUE (-4550 4175);
FORCEPROP 2 LAST PART_TYPE SMLF
J 0
(-4525 3750);
DISPLAY 1.021277 (-4525 3750);
FORCEPROP 2 LAST CDS_LIB pure_quanta
J 0
(-4450 4000);
DISPLAY INVISIBLE (-4450 4000);
FORCEPROP 1 LAST NEEDS_NO_SIZE TRUE
J 0
(-4450 4000);
DISPLAY 0.468085 (-4450 4000);
PAINT GREEN (-4450 4000);
DISPLAY INVISIBLE (-4450 4000);
FORCEPROP 1 LAST PATH I62
J 0
(-4250 4155);
DISPLAY 0.723404 (-4250 4155);
PAINT GREEN (-4250 4155);
DISPLAY INVISIBLE (-4250 4155);
FORCEPROP 1 LAST PART_NUMBER CV+15^0TZ04
J 0
(-4400 4175);
DISPLAY 0.489362 (-4400 4175);
PAINT SKYBLUE (-4400 4175);
DISPLAY INVISIBLE (-4400 4175);
FORCEADD UNIVERSAL_GND..1
(-4625 4650);
FORCEPROP 3 LASTPIN (-4625 4700) SIG_NAME GND\g
J 0
(-4615 4710);
DISPLAY 0.659574 (-4615 4710);
PAINT MONO (-4615 4710);
DISPLAY INVISIBLE (-4615 4710);
FORCEPROP 2 LAST CDS_LIB pure_quanta_power
J 0
(-4625 4650);
PAINT MONO (-4625 4650);
DISPLAY INVISIBLE (-4625 4650);
FORCEPROP 1 LAST HDL_POWER GND
J 1
(-4600 4575);
DISPLAY 0.872340 (-4600 4575);
PAINT GREEN (-4600 4575);
DISPLAY INVISIBLE (-4600 4575);
FORCEPROP 1 LAST PATH I63
J 0
(-4550 4650);
DISPLAY 0.872340 (-4550 4650);
PAINT AQUA (-4550 4650);
DISPLAY INVISIBLE (-4550 4650);
FORCEADD Q_CAP..1
(-5225 5025);
FORCEPROP 1 LAST LOCATION PC91_1
J 0
(-5175 5175);
DISPLAY 0.489362 (-5175 5175);
PAINT SKYBLUE (-5175 5175);
FORCEPROP 0 LAST $SEC 1
J 0
(-5175 5225);
DISPLAY 0.680851 (-5175 5225);
PAINT MONO (-5175 5225);
DISPLAY INVISIBLE (-5175 5225);
FORCEPROP 0 LAST CDS_SEC 1
J 0
(-5175 5225);
DISPLAY 1.021277 (-5175 5225);
DISPLAY INVISIBLE (-5175 5225);
FORCEPROP 1 LASTPIN (-5225 5125) $PN 1
J 0
(-5215 5105);
DISPLAY 0.489362 (-5215 5105);
PAINT MONO (-5215 5105);
FORCEPROP 1 LASTPIN (-5225 4925) $PN 2
J 0
(-5215 4905);
DISPLAY 0.489362 (-5215 4905);
PAINT MONO (-5215 4905);
FORCEPROP 1 LAST TOLERANCE 20%
J 0
(-5175 5025);
DISPLAY 0.489362 (-5175 5025);
PAINT SKYBLUE (-5175 5025);
FORCEPROP 1 LAST VOLTAGE 16V
J 0
(-5175 5075);
DISPLAY 0.489362 (-5175 5075);
PAINT SKYBLUE (-5175 5075);
FORCEPROP 1 LAST VALUE 22UF
J 0
(-5175 5125);
DISPLAY 0.489362 (-5175 5125);
PAINT SKYBLUE (-5175 5125);
FORCEPROP 1 LAST PACK_TYPE C0805
J 0
(-5175 4925);
DISPLAY 0.489362 (-5175 4925);
PAINT SKYBLUE (-5175 4925);
FORCEPROP 1 LAST MATERIAL X6S
J 0
(-5175 4975);
DISPLAY 0.489362 (-5175 4975);
PAINT SKYBLUE (-5175 4975);
FORCEPROP 2 LAST CDS_LIB pure_quanta
J 0
(-5225 5025);
DISPLAY INVISIBLE (-5225 5025);
FORCEPROP 1 LAST PATH I64
J 0
(-5175 5175);
DISPLAY 0.978723 (-5175 5175);
PAINT WHITE (-5175 5175);
DISPLAY INVISIBLE (-5175 5175);
FORCEPROP 1 LAST PART_NUMBER CH6223MEA01
J 0
(-5175 4875);
DISPLAY 0.489362 (-5175 4875);
PAINT SKYBLUE (-5175 4875);
DISPLAY INVISIBLE (-5175 4875);
FORCEADD Q_CAP..1
(-4850 5025);
FORCEPROP 1 LAST LOCATION PC95_1
J 0
(-4800 5175);
DISPLAY 0.489362 (-4800 5175);
PAINT SKYBLUE (-4800 5175);
FORCEPROP 0 LAST $SEC 1
J 0
(-4800 5225);
DISPLAY 0.680851 (-4800 5225);
PAINT MONO (-4800 5225);
DISPLAY INVISIBLE (-4800 5225);
FORCEPROP 0 LAST CDS_SEC 1
J 0
(-4800 5225);
DISPLAY 1.021277 (-4800 5225);
DISPLAY INVISIBLE (-4800 5225);
FORCEPROP 1 LASTPIN (-4850 5125) $PN 1
J 0
(-4840 5105);
DISPLAY 0.489362 (-4840 5105);
PAINT MONO (-4840 5105);
FORCEPROP 1 LASTPIN (-4850 4925) $PN 2
J 0
(-4840 4905);
DISPLAY 0.489362 (-4840 4905);
PAINT MONO (-4840 4905);
FORCEPROP 1 LAST TOLERANCE 20%
J 0
(-4800 5025);
DISPLAY 0.489362 (-4800 5025);
PAINT SKYBLUE (-4800 5025);
FORCEPROP 1 LAST VOLTAGE 16V
J 0
(-4800 5075);
DISPLAY 0.489362 (-4800 5075);
PAINT SKYBLUE (-4800 5075);
FORCEPROP 1 LAST VALUE 22UF
J 0
(-4800 5125);
DISPLAY 0.489362 (-4800 5125);
PAINT SKYBLUE (-4800 5125);
FORCEPROP 1 LAST MATERIAL X6S
J 0
(-4800 4975);
DISPLAY 0.489362 (-4800 4975);
PAINT SKYBLUE (-4800 4975);
FORCEPROP 1 LAST PACK_TYPE C0805
J 0
(-4800 4925);
DISPLAY 0.489362 (-4800 4925);
PAINT SKYBLUE (-4800 4925);
FORCEPROP 2 LAST CDS_LIB pure_quanta
J 0
(-4850 5025);
DISPLAY INVISIBLE (-4850 5025);
FORCEPROP 1 LAST PATH I65
J 0
(-4800 5175);
DISPLAY 0.978723 (-4800 5175);
PAINT WHITE (-4800 5175);
DISPLAY INVISIBLE (-4800 5175);
FORCEPROP 1 LAST PART_NUMBER CH6223MEA01
J 0
(-4800 4875);
DISPLAY 0.489362 (-4800 4875);
PAINT SKYBLUE (-4800 4875);
DISPLAY INVISIBLE (-4800 4875);
FORCEADD Q_CAPP..1
(-4425 5025);
FORCEPROP 1 LAST LOCATION PC101
J 0
(-4375 5150);
DISPLAY 0.489362 (-4375 5150);
PAINT SKYBLUE (-4375 5150);
FORCEPROP 0 LAST $SEC 1
J 0
(-4375 5200);
DISPLAY 0.680851 (-4375 5200);
PAINT MONO (-4375 5200);
DISPLAY INVISIBLE (-4375 5200);
FORCEPROP 0 LAST CDS_SEC 1
J 0
(-4375 5200);
DISPLAY 1.021277 (-4375 5200);
DISPLAY INVISIBLE (-4375 5200);
FORCEPROP 1 LASTPIN (-4425 5125) $PN 1
J 0
(-4415 5110);
DISPLAY 0.489362 (-4415 5110);
PAINT MONO (-4415 5110);
FORCEPROP 1 LASTPIN (-4425 4925) $PN 2
J 0
(-4415 4910);
DISPLAY 0.489362 (-4415 4910);
PAINT MONO (-4415 4910);
FORCEPROP 1 LAST VOLTAGE 16V
J 0
(-4375 5000);
DISPLAY 0.489362 (-4375 5000);
PAINT SKYBLUE (-4375 5000);
FORCEPROP 1 LAST VALUE 270UF
J 0
(-4375 5100);
DISPLAY 0.489362 (-4375 5100);
PAINT SKYBLUE (-4375 5100);
FORCEPROP 1 LAST MATERIAL OSCON
J 0
(-4375 4950);
DISPLAY 0.489362 (-4375 4950);
PAINT SKYBLUE (-4375 4950);
FORCEPROP 1 LAST TOLERANCE 20%
J 0
(-4375 5050);
DISPLAY 0.489362 (-4375 5050);
PAINT SKYBLUE (-4375 5050);
FORCEPROP 1 LAST PACK_TYPE THLF
J 0
(-4375 4900);
DISPLAY 0.489362 (-4375 4900);
PAINT SKYBLUE (-4375 4900);
FORCEPROP 2 LAST CDS_LIB pure_quanta
J 0
(-4425 5025);
DISPLAY INVISIBLE (-4425 5025);
FORCEPROP 1 LAST PATH I66
J 0
(-4375 5175);
DISPLAY 0.978723 (-4375 5175);
DISPLAY INVISIBLE (-4375 5175);
FORCEPROP 1 LAST PART_NUMBER CC72703MD38
J 0
(-4375 4850);
DISPLAY 0.489362 (-4375 4850);
PAINT SKYBLUE (-4375 4850);
DISPLAY INVISIBLE (-4375 4850);
FORCEADD VCC_CORE..1
(-4625 5375);
FORCEPROP 3 LASTPIN (-4625 5325) SIG_NAME SW_P12V_AUX_PVDDCR_CPU1_P0_FLT\g
J 0
(-4615 5335);
DISPLAY 0.659574 (-4615 5335);
PAINT MONO (-4615 5335);
DISPLAY INVISIBLE (-4615 5335);
FORCEPROP 1 LAST HDL_POWER SW_P12V_AUX_PVDDCR_CPU1_P0_FLT
J 1
(-4625 5425);
DISPLAY 0.489362 (-4625 5425);
PAINT GREEN (-4625 5425);
FORCEPROP 2 LAST CDS_LIB pure_quanta_power
J 0
(-4625 5375);
DISPLAY INVISIBLE (-4625 5375);
FORCEPROP 1 LAST PATH I67
J 0
(-4575 5400);
DISPLAY 0.872340 (-4575 5400);
PAINT AQUA (-4575 5400);
DISPLAY INVISIBLE (-4575 5400);
FORCEADD OFFPAGE..6
R 2
(-3275 925);
FORCEPROP 2 LAST $XR0 202 
J 0
(-3031 925);
DISPLAY 0.638298 (-3031 925);
PAINT MONO (-3031 925);
FORCEPROP 2 LAST CDS_LIB standard
J 0
(-3275 925);
DISPLAY INVISIBLE (-3275 925);
FORCEPROP 1 LAST OFFPAGE TRUE
J 2
(-3600 800);
DISPLAY 0.872340 (-3600 800);
PAINT GREEN (-3600 800);
DISPLAY INVISIBLE (-3600 800);
FORCEPROP 1 LAST COMMENT_BODY TRUE
J 2
(-3375 850);
DISPLAY 0.872340 (-3375 850);
PAINT GREEN (-3375 850);
DISPLAY INVISIBLE (-3375 850);
FORCEPROP 2 LAST PATH I68
J 0
(-3025 975);
DISPLAY 0.680851 (-3025 975);
DISPLAY INVISIBLE (-3025 975);
FORCEADD Q_CAP..1
(-2725 975);
FORCEPROP 1 LAST LOCATION PC106_2
J 0
(-2675 1100);
DISPLAY 0.489362 (-2675 1100);
PAINT SKYBLUE (-2675 1100);
FORCEPROP 0 LAST $SEC 1
J 0
(-2675 1150);
DISPLAY 0.680851 (-2675 1150);
PAINT MONO (-2675 1150);
DISPLAY INVISIBLE (-2675 1150);
FORCEPROP 0 LAST CDS_SEC 1
J 0
(-2675 1150);
DISPLAY 1.021277 (-2675 1150);
DISPLAY INVISIBLE (-2675 1150);
FORCEPROP 1 LASTPIN (-2725 1075) $PN 1
J 0
(-2715 1055);
DISPLAY 0.489362 (-2715 1055);
PAINT MONO (-2715 1055);
FORCEPROP 1 LASTPIN (-2725 875) $PN 2
J 0
(-2715 855);
DISPLAY 0.489362 (-2715 855);
PAINT MONO (-2715 855);
FORCEPROP 1 LAST PACK_TYPE C0805
J 0
(-2675 850);
DISPLAY 0.489362 (-2675 850);
PAINT SKYBLUE (-2675 850);
FORCEPROP 1 LAST MATERIAL X6S
J 0
(-2675 900);
DISPLAY 0.489362 (-2675 900);
PAINT SKYBLUE (-2675 900);
FORCEPROP 1 LAST TOLERANCE 20%
J 0
(-2675 950);
DISPLAY 0.489362 (-2675 950);
PAINT SKYBLUE (-2675 950);
FORCEPROP 1 LAST VALUE 22UF
J 0
(-2675 1050);
DISPLAY 0.489362 (-2675 1050);
PAINT SKYBLUE (-2675 1050);
FORCEPROP 1 LAST VOLTAGE 4V
J 0
(-2675 1000);
DISPLAY 0.489362 (-2675 1000);
PAINT SKYBLUE (-2675 1000);
FORCEPROP 2 LAST CDS_LIB pure_quanta
J 0
(-2725 975);
DISPLAY INVISIBLE (-2725 975);
FORCEPROP 1 LAST PATH I69
J 0
(-2675 1125);
DISPLAY 0.978723 (-2675 1125);
PAINT WHITE (-2675 1125);
DISPLAY INVISIBLE (-2675 1125);
FORCEPROP 1 LAST PART_NUMBER CH622KMEA03
J 0
(-2675 800);
DISPLAY 0.489362 (-2675 800);
PAINT SKYBLUE (-2675 800);
DISPLAY INVISIBLE (-2675 800);
FORCEADD OFFPAGE..5
(-8600 1175);
FORCEPROP 2 LAST $XR0 200 
J 0
(-8855 1175);
DISPLAY 0.638298 (-8855 1175);
PAINT MONO (-8855 1175);
FORCEPROP 2 LAST CDS_LIB standard
J 0
(-8600 1175);
DISPLAY INVISIBLE (-8600 1175);
FORCEPROP 1 LAST OFFPAGE TRUE
J 0
(-8275 1050);
DISPLAY 0.872340 (-8275 1050);
PAINT GREEN (-8275 1050);
DISPLAY INVISIBLE (-8275 1050);
FORCEPROP 1 LAST COMMENT_BODY TRUE
J 0
(-8500 1100);
DISPLAY 0.872340 (-8500 1100);
PAINT GREEN (-8500 1100);
DISPLAY INVISIBLE (-8500 1100);
FORCEPROP 2 LAST PATH I7
J 0
(-8875 1225);
DISPLAY 0.680851 (-8875 1225);
DISPLAY INVISIBLE (-8875 1225);
FORCEADD Q_CAPP..1
(-3700 2675);
FORCEPROP 1 LAST LOCATION PC102
J 0
(-3650 2775);
DISPLAY 0.489362 (-3650 2775);
PAINT SKYBLUE (-3650 2775);
FORCEPROP 0 LAST $SEC 1
J 0
(-3650 2825);
DISPLAY 0.680851 (-3650 2825);
PAINT MONO (-3650 2825);
DISPLAY INVISIBLE (-3650 2825);
FORCEPROP 0 LAST CDS_SEC 1
J 0
(-3650 2825);
DISPLAY 1.021277 (-3650 2825);
DISPLAY INVISIBLE (-3650 2825);
FORCEPROP 1 LASTPIN (-3700 2775) $PN 1
J 0
(-3690 2760);
DISPLAY 0.489362 (-3690 2760);
PAINT MONO (-3690 2760);
FORCEPROP 1 LASTPIN (-3700 2575) $PN 2
J 0
(-3690 2560);
DISPLAY 0.489362 (-3690 2560);
PAINT MONO (-3690 2560);
FORCEPROP 1 LAST PACK_TYPE SMLF
J 0
(-3650 2525);
DISPLAY 0.489362 (-3650 2525);
PAINT SKYBLUE (-3650 2525);
FORCEPROP 1 LAST TOLERANCE 20%
J 0
(-3650 2675);
DISPLAY 0.489362 (-3650 2675);
PAINT SKYBLUE (-3650 2675);
FORCEPROP 1 LAST MATERIAL SPCAP
J 0
(-3650 2575);
DISPLAY 0.489362 (-3650 2575);
PAINT SKYBLUE (-3650 2575);
FORCEPROP 1 LAST VALUE 220UF
J 0
(-3650 2725);
DISPLAY 0.489362 (-3650 2725);
PAINT SKYBLUE (-3650 2725);
FORCEPROP 1 LAST VOLTAGE 4V
J 0
(-3650 2625);
DISPLAY 0.489362 (-3650 2625);
PAINT SKYBLUE (-3650 2625);
FORCEPROP 2 LAST CDS_LIB pure_quanta
J 0
(-3700 2675);
DISPLAY INVISIBLE (-3700 2675);
FORCEPROP 1 LAST PATH I70
J 0
(-3650 2825);
DISPLAY 0.978723 (-3650 2825);
DISPLAY INVISIBLE (-3650 2825);
FORCEPROP 1 LAST PART_NUMBER CH122KM8801
J 0
(-3650 2475);
DISPLAY 0.489362 (-3650 2475);
PAINT SKYBLUE (-3650 2475);
DISPLAY INVISIBLE (-3650 2475);
FORCEADD Q_CAPP..1
(-3350 2675);
FORCEPROP 1 LAST LOCATION PC97
J 0
(-3300 2775);
DISPLAY 0.489362 (-3300 2775);
PAINT SKYBLUE (-3300 2775);
FORCEPROP 0 LAST $SEC 1
J 0
(-3300 2825);
DISPLAY 0.680851 (-3300 2825);
PAINT MONO (-3300 2825);
DISPLAY INVISIBLE (-3300 2825);
FORCEPROP 0 LAST CDS_SEC 1
J 0
(-3300 2825);
DISPLAY 1.021277 (-3300 2825);
DISPLAY INVISIBLE (-3300 2825);
FORCEPROP 1 LASTPIN (-3350 2775) $PN 1
J 0
(-3340 2760);
DISPLAY 0.489362 (-3340 2760);
PAINT MONO (-3340 2760);
FORCEPROP 1 LASTPIN (-3350 2575) $PN 2
J 0
(-3340 2560);
DISPLAY 0.489362 (-3340 2560);
PAINT MONO (-3340 2560);
FORCEPROP 1 LAST PACK_TYPE SMLF
J 0
(-3300 2525);
DISPLAY 0.489362 (-3300 2525);
PAINT SKYBLUE (-3300 2525);
FORCEPROP 1 LAST VALUE 220UF
J 0
(-3300 2725);
DISPLAY 0.489362 (-3300 2725);
PAINT SKYBLUE (-3300 2725);
FORCEPROP 1 LAST VOLTAGE 4V
J 0
(-3300 2625);
DISPLAY 0.489362 (-3300 2625);
PAINT SKYBLUE (-3300 2625);
FORCEPROP 1 LAST TOLERANCE 20%
J 0
(-3300 2675);
DISPLAY 0.489362 (-3300 2675);
PAINT SKYBLUE (-3300 2675);
FORCEPROP 1 LAST MATERIAL SPCAP
J 0
(-3300 2575);
DISPLAY 0.489362 (-3300 2575);
PAINT SKYBLUE (-3300 2575);
FORCEPROP 2 LAST CDS_LIB pure_quanta
J 0
(-3350 2675);
DISPLAY INVISIBLE (-3350 2675);
FORCEPROP 1 LAST PATH I71
J 0
(-3300 2825);
DISPLAY 0.978723 (-3300 2825);
DISPLAY INVISIBLE (-3300 2825);
FORCEPROP 1 LAST PART_NUMBER CH122KM8801
J 0
(-3300 2475);
DISPLAY 0.489362 (-3300 2475);
PAINT SKYBLUE (-3300 2475);
DISPLAY INVISIBLE (-3300 2475);
FORCEADD Q_CAPP..1
(-3025 2675);
FORCEPROP 1 LAST LOCATION PC98
J 0
(-2975 2775);
DISPLAY 0.489362 (-2975 2775);
PAINT SKYBLUE (-2975 2775);
FORCEPROP 0 LAST $SEC 1
J 0
(-2975 2825);
DISPLAY 0.680851 (-2975 2825);
PAINT MONO (-2975 2825);
DISPLAY INVISIBLE (-2975 2825);
FORCEPROP 0 LAST CDS_SEC 1
J 0
(-2975 2825);
DISPLAY 1.021277 (-2975 2825);
DISPLAY INVISIBLE (-2975 2825);
FORCEPROP 1 LASTPIN (-3025 2775) $PN 1
J 0
(-3015 2760);
DISPLAY 0.489362 (-3015 2760);
PAINT MONO (-3015 2760);
FORCEPROP 1 LASTPIN (-3025 2575) $PN 2
J 0
(-3015 2560);
DISPLAY 0.489362 (-3015 2560);
PAINT MONO (-3015 2560);
FORCEPROP 1 LAST VALUE 220UF
J 0
(-2975 2725);
DISPLAY 0.489362 (-2975 2725);
PAINT SKYBLUE (-2975 2725);
FORCEPROP 1 LAST TOLERANCE 20%
J 0
(-2975 2675);
DISPLAY 0.489362 (-2975 2675);
PAINT SKYBLUE (-2975 2675);
FORCEPROP 1 LAST MATERIAL SPCAP
J 0
(-2975 2575);
DISPLAY 0.489362 (-2975 2575);
PAINT SKYBLUE (-2975 2575);
FORCEPROP 1 LAST PACK_TYPE SMLF
J 0
(-2975 2525);
DISPLAY 0.489362 (-2975 2525);
PAINT SKYBLUE (-2975 2525);
FORCEPROP 1 LAST VOLTAGE 4V
J 0
(-2975 2625);
DISPLAY 0.489362 (-2975 2625);
PAINT SKYBLUE (-2975 2625);
FORCEPROP 2 LAST CDS_LIB pure_quanta
J 0
(-3025 2675);
DISPLAY INVISIBLE (-3025 2675);
FORCEPROP 1 LAST PATH I72
J 0
(-2975 2825);
DISPLAY 0.978723 (-2975 2825);
DISPLAY INVISIBLE (-2975 2825);
FORCEPROP 1 LAST PART_NUMBER CH122KM8801
J 0
(-2975 2475);
DISPLAY 0.489362 (-2975 2475);
PAINT SKYBLUE (-2975 2475);
DISPLAY INVISIBLE (-2975 2475);
FORCEADD Q_CAPP..1
(-2700 2675);
FORCEPROP 1 LAST LOCATION PC100
J 0
(-2650 2775);
DISPLAY 0.489362 (-2650 2775);
PAINT SKYBLUE (-2650 2775);
FORCEPROP 0 LAST $SEC 1
J 0
(-2650 2825);
DISPLAY 0.680851 (-2650 2825);
PAINT MONO (-2650 2825);
DISPLAY INVISIBLE (-2650 2825);
FORCEPROP 0 LAST CDS_SEC 1
J 0
(-2650 2825);
DISPLAY 1.021277 (-2650 2825);
DISPLAY INVISIBLE (-2650 2825);
FORCEPROP 1 LASTPIN (-2700 2775) $PN 1
J 0
(-2690 2760);
DISPLAY 0.489362 (-2690 2760);
PAINT MONO (-2690 2760);
FORCEPROP 1 LASTPIN (-2700 2575) $PN 2
J 0
(-2690 2560);
DISPLAY 0.489362 (-2690 2560);
PAINT MONO (-2690 2560);
FORCEPROP 1 LAST MATERIAL SPCAP
J 0
(-2650 2575);
DISPLAY 0.489362 (-2650 2575);
PAINT SKYBLUE (-2650 2575);
FORCEPROP 1 LAST TOLERANCE 20%
J 0
(-2650 2675);
DISPLAY 0.489362 (-2650 2675);
PAINT SKYBLUE (-2650 2675);
FORCEPROP 1 LAST VALUE 220UF
J 0
(-2650 2725);
DISPLAY 0.489362 (-2650 2725);
PAINT SKYBLUE (-2650 2725);
FORCEPROP 1 LAST VOLTAGE 4V
J 0
(-2650 2625);
DISPLAY 0.489362 (-2650 2625);
PAINT SKYBLUE (-2650 2625);
FORCEPROP 1 LAST PACK_TYPE SMLF
J 0
(-2650 2525);
DISPLAY 0.489362 (-2650 2525);
PAINT SKYBLUE (-2650 2525);
FORCEPROP 2 LAST CDS_LIB pure_quanta
J 0
(-2700 2675);
DISPLAY INVISIBLE (-2700 2675);
FORCEPROP 1 LAST PATH I73
J 0
(-2650 2825);
DISPLAY 0.978723 (-2650 2825);
DISPLAY INVISIBLE (-2650 2825);
FORCEPROP 1 LAST PART_NUMBER CH122KM8801
J 0
(-2650 2475);
DISPLAY 0.489362 (-2650 2475);
PAINT SKYBLUE (-2650 2475);
DISPLAY INVISIBLE (-2650 2475);
FORCEADD UNIVERSAL_GND..1
(-2400 2300);
FORCEPROP 3 LASTPIN (-2400 2350) SIG_NAME GND\g
J 0
(-2390 2360);
DISPLAY 0.659574 (-2390 2360);
PAINT MONO (-2390 2360);
DISPLAY INVISIBLE (-2390 2360);
FORCEPROP 2 LAST CDS_LIB pure_quanta_power
J 0
(-2400 2300);
DISPLAY INVISIBLE (-2400 2300);
FORCEPROP 1 LAST HDL_POWER GND
J 1
(-2375 2225);
DISPLAY 0.872340 (-2375 2225);
PAINT GREEN (-2375 2225);
DISPLAY INVISIBLE (-2375 2225);
FORCEPROP 1 LAST PATH I74
J 0
(-2325 2300);
DISPLAY 0.872340 (-2325 2300);
PAINT AQUA (-2325 2300);
DISPLAY INVISIBLE (-2325 2300);
FORCEADD Q_CAPP..1
(-2400 2675);
FORCEPROP 1 LAST LOCATION PC103
J 0
(-2350 2775);
DISPLAY 0.489362 (-2350 2775);
PAINT SKYBLUE (-2350 2775);
FORCEPROP 0 LAST $SEC 1
J 0
(-2350 2825);
DISPLAY 0.680851 (-2350 2825);
PAINT MONO (-2350 2825);
DISPLAY INVISIBLE (-2350 2825);
FORCEPROP 0 LAST CDS_SEC 1
J 0
(-2350 2825);
DISPLAY 1.021277 (-2350 2825);
DISPLAY INVISIBLE (-2350 2825);
FORCEPROP 1 LASTPIN (-2400 2775) $PN 1
J 0
(-2390 2760);
DISPLAY 0.489362 (-2390 2760);
PAINT MONO (-2390 2760);
FORCEPROP 1 LASTPIN (-2400 2575) $PN 2
J 0
(-2390 2560);
DISPLAY 0.489362 (-2390 2560);
PAINT MONO (-2390 2560);
FORCEPROP 1 LAST MATERIAL SPCAP
J 0
(-2350 2575);
DISPLAY 0.489362 (-2350 2575);
PAINT SKYBLUE (-2350 2575);
FORCEPROP 1 LAST TOLERANCE 20%
J 0
(-2350 2675);
DISPLAY 0.489362 (-2350 2675);
PAINT SKYBLUE (-2350 2675);
FORCEPROP 1 LAST VALUE 220UF
J 0
(-2350 2725);
DISPLAY 0.489362 (-2350 2725);
PAINT SKYBLUE (-2350 2725);
FORCEPROP 1 LAST VOLTAGE 4V
J 0
(-2350 2625);
DISPLAY 0.489362 (-2350 2625);
PAINT SKYBLUE (-2350 2625);
FORCEPROP 1 LAST PACK_TYPE SMLF
J 0
(-2350 2525);
DISPLAY 0.489362 (-2350 2525);
PAINT SKYBLUE (-2350 2525);
FORCEPROP 2 LAST CDS_LIB pure_quanta
J 0
(-2400 2675);
DISPLAY INVISIBLE (-2400 2675);
FORCEPROP 1 LAST PATH I75
J 0
(-2350 2825);
DISPLAY 0.978723 (-2350 2825);
DISPLAY INVISIBLE (-2350 2825);
FORCEPROP 1 LAST PART_NUMBER CH122KM8801
J 0
(-2350 2475);
DISPLAY 0.489362 (-2350 2475);
PAINT SKYBLUE (-2350 2475);
DISPLAY INVISIBLE (-2350 2475);
FORCEADD VCC_CORE..1
(-2400 2975);
FORCEPROP 3 LASTPIN (-2400 2925) SIG_NAME PVDDCR_CPU1_P0\g
J 0
(-2390 2935);
DISPLAY 0.659574 (-2390 2935);
PAINT MONO (-2390 2935);
DISPLAY INVISIBLE (-2390 2935);
FORCEPROP 1 LAST HDL_POWER PVDDCR_CPU1_P0
J 1
(-2400 3025);
DISPLAY 0.489362 (-2400 3025);
PAINT GREEN (-2400 3025);
FORCEPROP 2 LAST CDS_LIB pure_quanta_power
J 0
(-2400 2975);
DISPLAY INVISIBLE (-2400 2975);
FORCEPROP 1 LAST PATH I76
J 0
(-2350 3000);
DISPLAY 0.872340 (-2350 3000);
PAINT AQUA (-2350 3000);
DISPLAY INVISIBLE (-2350 3000);
FORCEADD Q_CAP..1
(-2300 975);
FORCEPROP 1 LAST LOCATION PC108_2
J 0
(-2250 1100);
DISPLAY 0.489362 (-2250 1100);
PAINT SKYBLUE (-2250 1100);
FORCEPROP 0 LAST $SEC 1
J 0
(-2250 1150);
DISPLAY 0.680851 (-2250 1150);
PAINT MONO (-2250 1150);
DISPLAY INVISIBLE (-2250 1150);
FORCEPROP 0 LAST CDS_SEC 1
J 0
(-2250 1150);
DISPLAY 1.021277 (-2250 1150);
DISPLAY INVISIBLE (-2250 1150);
FORCEPROP 1 LASTPIN (-2300 1075) $PN 1
J 0
(-2290 1055);
DISPLAY 0.489362 (-2290 1055);
PAINT MONO (-2290 1055);
FORCEPROP 1 LASTPIN (-2300 875) $PN 2
J 0
(-2290 855);
DISPLAY 0.489362 (-2290 855);
PAINT MONO (-2290 855);
FORCEPROP 1 LAST PACK_TYPE C0805
J 0
(-2250 850);
DISPLAY 0.489362 (-2250 850);
PAINT SKYBLUE (-2250 850);
FORCEPROP 1 LAST MATERIAL X6S
J 0
(-2250 900);
DISPLAY 0.489362 (-2250 900);
PAINT SKYBLUE (-2250 900);
FORCEPROP 1 LAST TOLERANCE 20%
J 0
(-2250 950);
DISPLAY 0.489362 (-2250 950);
PAINT SKYBLUE (-2250 950);
FORCEPROP 1 LAST VALUE 22UF
J 0
(-2250 1050);
DISPLAY 0.489362 (-2250 1050);
PAINT SKYBLUE (-2250 1050);
FORCEPROP 1 LAST VOLTAGE 4V
J 0
(-2250 1000);
DISPLAY 0.489362 (-2250 1000);
PAINT SKYBLUE (-2250 1000);
FORCEPROP 2 LAST CDS_LIB pure_quanta
J 0
(-2300 975);
DISPLAY INVISIBLE (-2300 975);
FORCEPROP 1 LAST PATH I77
J 0
(-2250 1125);
DISPLAY 0.978723 (-2250 1125);
PAINT WHITE (-2250 1125);
DISPLAY INVISIBLE (-2250 1125);
FORCEPROP 1 LAST PART_NUMBER CH622KMEA03
J 0
(-2250 800);
DISPLAY 0.489362 (-2250 800);
PAINT SKYBLUE (-2250 800);
DISPLAY INVISIBLE (-2250 800);
FORCEADD UNIVERSAL_GND..1
(-2300 625);
FORCEPROP 3 LASTPIN (-2300 675) SIG_NAME GND\g
J 0
(-2290 685);
DISPLAY 0.659574 (-2290 685);
PAINT MONO (-2290 685);
DISPLAY INVISIBLE (-2290 685);
FORCEPROP 2 LAST CDS_LIB pure_quanta_power
J 0
(-2300 625);
PAINT MONO (-2300 625);
DISPLAY INVISIBLE (-2300 625);
FORCEPROP 1 LAST HDL_POWER GND
J 1
(-2275 550);
DISPLAY 0.872340 (-2275 550);
PAINT GREEN (-2275 550);
DISPLAY INVISIBLE (-2275 550);
FORCEPROP 1 LAST PATH I78
J 0
(-2225 625);
DISPLAY 0.872340 (-2225 625);
PAINT AQUA (-2225 625);
DISPLAY INVISIBLE (-2225 625);
FORCEADD VCC_CORE..1
(-2300 1275);
FORCEPROP 3 LASTPIN (-2300 1225) SIG_NAME PVDDCR_CPU1_P0\g
J 0
(-2290 1235);
DISPLAY 0.659574 (-2290 1235);
PAINT MONO (-2290 1235);
DISPLAY INVISIBLE (-2290 1235);
FORCEPROP 1 LAST HDL_POWER PVDDCR_CPU1_P0
J 1
(-2300 1325);
DISPLAY 0.489362 (-2300 1325);
PAINT GREEN (-2300 1325);
FORCEPROP 2 LAST CDS_LIB pure_quanta_power
J 0
(-2300 1275);
DISPLAY INVISIBLE (-2300 1275);
FORCEPROP 1 LAST PATH I79
J 0
(-2250 1300);
DISPLAY 0.872340 (-2250 1300);
PAINT AQUA (-2250 1300);
DISPLAY INVISIBLE (-2250 1300);
FORCEADD OFFPAGE..1
(-8600 1075);
FORCEPROP 2 LAST $XR5 206 
J 0
(-9452 1075);
DISPLAY 0.638298 (-9452 1075);
PAINT MONO (-9452 1075);
FORCEPROP 2 LAST $XR4 205 
J 0
(-9332 1075);
DISPLAY 0.638298 (-9332 1075);
PAINT MONO (-9332 1075);
FORCEPROP 2 LAST $XR3 203 
J 0
(-9212 1075);
DISPLAY 0.638298 (-9212 1075);
PAINT MONO (-9212 1075);
FORCEPROP 2 LAST $XR2 202 
J 0
(-9092 1075);
DISPLAY 0.638298 (-9092 1075);
PAINT MONO (-9092 1075);
FORCEPROP 2 LAST $XR1 201 
J 0
(-8972 1075);
DISPLAY 0.638298 (-8972 1075);
PAINT MONO (-8972 1075);
FORCEPROP 2 LAST $XR0 200 
J 0
(-8852 1075);
DISPLAY 0.638298 (-8852 1075);
PAINT MONO (-8852 1075);
FORCEPROP 2 LAST CDS_LIB standard
J 0
(-8600 1075);
DISPLAY INVISIBLE (-8600 1075);
FORCEPROP 1 LAST OFFPAGE TRUE
J 0
(-8275 950);
DISPLAY 0.872340 (-8275 950);
PAINT GREEN (-8275 950);
DISPLAY INVISIBLE (-8275 950);
FORCEPROP 1 LAST COMMENT_BODY TRUE
J 0
(-8475 975);
DISPLAY 0.872340 (-8475 975);
PAINT GREEN (-8475 975);
DISPLAY INVISIBLE (-8475 975);
FORCEPROP 2 LAST PATH I8
J 0
(-8850 1125);
DISPLAY 0.680851 (-8850 1125);
DISPLAY INVISIBLE (-8850 1125);
FORCEADD UNIVERSAL_GND..1
(-1850 3575);
FORCEPROP 3 LASTPIN (-1850 3625) SIG_NAME GND\g
J 0
(-1840 3635);
DISPLAY 0.659574 (-1840 3635);
PAINT MONO (-1840 3635);
DISPLAY INVISIBLE (-1840 3635);
FORCEPROP 2 LAST CDS_LIB pure_quanta_power
J 0
(-1850 3575);
PAINT MONO (-1850 3575);
DISPLAY INVISIBLE (-1850 3575);
FORCEPROP 1 LAST HDL_POWER GND
J 1
(-1825 3500);
DISPLAY 0.872340 (-1825 3500);
PAINT GREEN (-1825 3500);
DISPLAY INVISIBLE (-1825 3500);
FORCEPROP 1 LAST PATH I80
J 0
(-1775 3575);
DISPLAY 0.872340 (-1775 3575);
PAINT AQUA (-1775 3575);
DISPLAY INVISIBLE (-1775 3575);
FORCEADD OFFPAGE..6
R 2
(-3550 3875);
FORCEPROP 2 LAST $XR0 201 
J 0
(-3336 3875);
DISPLAY 0.638298 (-3336 3875);
PAINT MONO (-3336 3875);
FORCEPROP 2 LAST CDS_LIB standard
J 2
(-3550 3875);
DISPLAY INVISIBLE (-3550 3875);
FORCEPROP 1 LAST OFFPAGE TRUE
J 2
(-3875 3750);
DISPLAY 0.872340 (-3875 3750);
PAINT GREEN (-3875 3750);
DISPLAY INVISIBLE (-3875 3750);
FORCEPROP 1 LAST COMMENT_BODY TRUE
J 2
(-3650 3800);
DISPLAY 0.872340 (-3650 3800);
PAINT GREEN (-3650 3800);
DISPLAY INVISIBLE (-3650 3800);
FORCEPROP 2 LAST PATH I81
J 0
(-3325 3925);
DISPLAY 0.680851 (-3325 3925);
DISPLAY INVISIBLE (-3325 3925);
FORCEADD Q_CAPP..1
(-4025 5025);
FORCEPROP 1 LAST LOCATION PC104
J 0
(-3975 5150);
DISPLAY 0.489362 (-3975 5150);
PAINT SKYBLUE (-3975 5150);
FORCEPROP 0 LAST $SEC 1
J 0
(-3975 5200);
DISPLAY 0.680851 (-3975 5200);
PAINT MONO (-3975 5200);
DISPLAY INVISIBLE (-3975 5200);
FORCEPROP 0 LAST CDS_SEC 1
J 0
(-3975 5200);
DISPLAY 1.021277 (-3975 5200);
DISPLAY INVISIBLE (-3975 5200);
FORCEPROP 1 LASTPIN (-4025 5125) $PN 1
J 0
(-4015 5110);
DISPLAY 0.489362 (-4015 5110);
PAINT MONO (-4015 5110);
FORCEPROP 1 LASTPIN (-4025 4925) $PN 2
J 0
(-4015 4910);
DISPLAY 0.489362 (-4015 4910);
PAINT MONO (-4015 4910);
FORCEPROP 1 LAST VOLTAGE 16V
J 0
(-3975 5000);
DISPLAY 0.489362 (-3975 5000);
PAINT SKYBLUE (-3975 5000);
FORCEPROP 1 LAST VALUE 270UF
J 0
(-3975 5100);
DISPLAY 0.489362 (-3975 5100);
PAINT SKYBLUE (-3975 5100);
FORCEPROP 1 LAST PACK_TYPE THLF
J 0
(-3975 4900);
DISPLAY 0.489362 (-3975 4900);
PAINT SKYBLUE (-3975 4900);
FORCEPROP 1 LAST TOLERANCE 20%
J 0
(-3975 5050);
DISPLAY 0.489362 (-3975 5050);
PAINT SKYBLUE (-3975 5050);
FORCEPROP 1 LAST MATERIAL OSCON
J 0
(-3975 4950);
DISPLAY 0.489362 (-3975 4950);
PAINT SKYBLUE (-3975 4950);
FORCEPROP 2 LAST CDS_LIB pure_quanta
J 0
(-4025 5025);
DISPLAY INVISIBLE (-4025 5025);
FORCEPROP 1 LAST PATH I82
J 0
(-3975 5175);
DISPLAY 0.978723 (-3975 5175);
DISPLAY INVISIBLE (-3975 5175);
FORCEPROP 1 LAST PART_NUMBER CC72703MD38
J 0
(-3975 4850);
DISPLAY 0.489362 (-3975 4850);
PAINT SKYBLUE (-3975 4850);
DISPLAY INVISIBLE (-3975 4850);
FORCEADD Q_INDUCTOR..1
(-3625 5300);
FORCEPROP 1 LAST LOCATION PL12
J 0
(-3475 5300);
DISPLAY 0.489362 (-3475 5300);
PAINT SKYBLUE (-3475 5300);
FORCEPROP 2 LAST $SEC 1
J 0
(-3750 5575);
DISPLAY 0.680851 (-3750 5575);
PAINT MONO (-3750 5575);
DISPLAY INVISIBLE (-3750 5575);
FORCEPROP 0 LAST CDS_SEC 1
J 0
(-3650 5400);
DISPLAY 1.021277 (-3650 5400);
DISPLAY INVISIBLE (-3650 5400);
FORCEPROP 2 LASTPIN (-3725 5275) $PN 1
J 2
(-3735 5285);
DISPLAY 0.489362 (-3735 5285);
FORCEPROP 2 LASTPIN (-3525 5275) $PN 2
J 0
(-3515 5285);
DISPLAY 0.489362 (-3515 5285);
FORCEPROP 1 LAST MATERIAL IND
J 0
(-3750 5355);
DISPLAY 0.489362 (-3750 5355);
PAINT SKYBLUE (-3750 5355);
FORCEPROP 2 LAST PACK_TYPE SMLF
J 0
(-3750 5525);
DISPLAY 0.489362 (-3750 5525);
PAINT SKYBLUE (-3750 5525);
FORCEPROP 2 LAST VALUE 50NH/86A
J 0
(-3750 5475);
DISPLAY 0.489362 (-3750 5475);
PAINT SKYBLUE (-3750 5475);
FORCEPROP 1 LAST NEEDS_NO_SIZE TRUE
J 0
(-3625 5300);
DISPLAY 0.468085 (-3625 5300);
PAINT GREEN (-3625 5300);
DISPLAY INVISIBLE (-3625 5300);
FORCEPROP 2 LAST CDS_LIB pure_quanta
J 0
(-3625 5300);
PAINT MONO (-3625 5300);
DISPLAY INVISIBLE (-3625 5300);
FORCEPROP 1 LAST PATH I83
J 0
(-3550 5355);
DISPLAY 0.723404 (-3550 5355);
PAINT GREEN (-3550 5355);
DISPLAY INVISIBLE (-3550 5355);
FORCEPROP 1 LAST PART_NUMBER CVA50^0MZ09
J 0
(-3750 5410);
DISPLAY 0.489362 (-3750 5410);
PAINT SKYBLUE (-3750 5410);
DISPLAY INVISIBLE (-3750 5410);
FORCEADD Q_CAP..1
(-2975 3925);
FORCEPROP 1 LAST LOCATION PC99
J 0
(-2925 4050);
DISPLAY 0.489362 (-2925 4050);
PAINT SKYBLUE (-2925 4050);
FORCEPROP 0 LAST $SEC 1
J 0
(-2925 4100);
DISPLAY 0.680851 (-2925 4100);
PAINT MONO (-2925 4100);
DISPLAY INVISIBLE (-2925 4100);
FORCEPROP 0 LAST CDS_SEC 1
J 0
(-2925 4100);
DISPLAY 1.021277 (-2925 4100);
DISPLAY INVISIBLE (-2925 4100);
FORCEPROP 1 LASTPIN (-2975 4025) $PN 1
J 0
(-2965 4005);
DISPLAY 0.489362 (-2965 4005);
PAINT MONO (-2965 4005);
FORCEPROP 1 LASTPIN (-2975 3825) $PN 2
J 0
(-2965 3805);
DISPLAY 0.489362 (-2965 3805);
PAINT MONO (-2965 3805);
FORCEPROP 1 LAST PACK_TYPE 0402
J 0
(-2925 3800);
DISPLAY 0.489362 (-2925 3800);
PAINT SKYBLUE (-2925 3800);
FORCEPROP 1 LAST VOLTAGE 25V
J 0
(-2925 3950);
DISPLAY 0.489362 (-2925 3950);
PAINT SKYBLUE (-2925 3950);
FORCEPROP 1 LAST VALUE 0.1UF
J 0
(-2925 4000);
DISPLAY 0.489362 (-2925 4000);
PAINT SKYBLUE (-2925 4000);
FORCEPROP 1 LAST TOLERANCE 10%
J 0
(-2925 3900);
DISPLAY 0.489362 (-2925 3900);
PAINT SKYBLUE (-2925 3900);
FORCEPROP 1 LAST MATERIAL X7R
J 0
(-2925 3850);
DISPLAY 0.489362 (-2925 3850);
PAINT SKYBLUE (-2925 3850);
FORCEPROP 2 LAST CDS_LIB pure_quanta
J 0
(-2975 3925);
DISPLAY INVISIBLE (-2975 3925);
FORCEPROP 1 LAST PATH I84
J 0
(-2925 4075);
DISPLAY 0.978723 (-2925 4075);
PAINT WHITE (-2925 4075);
DISPLAY INVISIBLE (-2925 4075);
FORCEPROP 1 LAST PART_NUMBER CH4104K1B00
J 0
(-2925 3750);
DISPLAY 0.489362 (-2925 3750);
PAINT SKYBLUE (-2925 3750);
DISPLAY INVISIBLE (-2925 3750);
FORCEADD UNIVERSAL_GND..1
(-3250 4725);
FORCEPROP 3 LASTPIN (-3250 4775) SIG_NAME GND\g
J 0
(-3240 4785);
DISPLAY 0.659574 (-3240 4785);
PAINT MONO (-3240 4785);
DISPLAY INVISIBLE (-3240 4785);
FORCEPROP 2 LAST CDS_LIB pure_quanta_power
J 0
(-3250 4725);
DISPLAY INVISIBLE (-3250 4725);
FORCEPROP 1 LAST HDL_POWER GND
J 1
(-3225 4650);
DISPLAY 0.872340 (-3225 4650);
PAINT GREEN (-3225 4650);
DISPLAY INVISIBLE (-3225 4650);
FORCEPROP 1 LAST PATH I85
J 0
(-3175 4725);
DISPLAY 0.872340 (-3175 4725);
PAINT AQUA (-3175 4725);
DISPLAY INVISIBLE (-3175 4725);
FORCEADD Q_CAP..1
(-2575 3925);
FORCEPROP 1 LAST LOCATION PC102_1
J 0
(-2525 4050);
DISPLAY 0.489362 (-2525 4050);
PAINT SKYBLUE (-2525 4050);
FORCEPROP 0 LAST $SEC 1
J 0
(-2525 4100);
DISPLAY 0.680851 (-2525 4100);
PAINT MONO (-2525 4100);
DISPLAY INVISIBLE (-2525 4100);
FORCEPROP 0 LAST CDS_SEC 1
J 0
(-2525 4100);
DISPLAY 1.021277 (-2525 4100);
DISPLAY INVISIBLE (-2525 4100);
FORCEPROP 1 LASTPIN (-2575 4025) $PN 1
J 0
(-2565 4005);
DISPLAY 0.489362 (-2565 4005);
PAINT MONO (-2565 4005);
FORCEPROP 1 LASTPIN (-2575 3825) $PN 2
J 0
(-2565 3805);
DISPLAY 0.489362 (-2565 3805);
PAINT MONO (-2565 3805);
FORCEPROP 1 LAST PACK_TYPE C0805
J 0
(-2525 3800);
DISPLAY 0.489362 (-2525 3800);
PAINT SKYBLUE (-2525 3800);
FORCEPROP 1 LAST MATERIAL X6S
J 0
(-2525 3850);
DISPLAY 0.489362 (-2525 3850);
PAINT SKYBLUE (-2525 3850);
FORCEPROP 1 LAST TOLERANCE 20%
J 0
(-2525 3900);
DISPLAY 0.489362 (-2525 3900);
PAINT SKYBLUE (-2525 3900);
FORCEPROP 1 LAST VALUE 22UF
J 0
(-2525 4000);
DISPLAY 0.489362 (-2525 4000);
PAINT SKYBLUE (-2525 4000);
FORCEPROP 1 LAST VOLTAGE 4V
J 0
(-2525 3950);
DISPLAY 0.489362 (-2525 3950);
PAINT SKYBLUE (-2525 3950);
FORCEPROP 2 LAST CDS_LIB pure_quanta
J 0
(-2575 3925);
DISPLAY INVISIBLE (-2575 3925);
FORCEPROP 1 LAST PATH I86
J 0
(-2525 4075);
DISPLAY 0.978723 (-2525 4075);
PAINT WHITE (-2525 4075);
DISPLAY INVISIBLE (-2525 4075);
FORCEPROP 1 LAST PART_NUMBER CH622KMEA03
J 0
(-2525 3750);
DISPLAY 0.489362 (-2525 3750);
PAINT SKYBLUE (-2525 3750);
DISPLAY INVISIBLE (-2525 3750);
FORCEADD Q_CAP..1
(-3250 5050);
FORCEPROP 1 LAST LOCATION PC85
J 0
(-3200 5200);
DISPLAY 0.489362 (-3200 5200);
PAINT SKYBLUE (-3200 5200);
FORCEPROP 0 LAST $SEC 1
J 0
(-3200 5225);
DISPLAY 0.680851 (-3200 5225);
PAINT MONO (-3200 5225);
DISPLAY INVISIBLE (-3200 5225);
FORCEPROP 0 LAST CDS_SEC 1
J 0
(-3200 5225);
DISPLAY 0.680851 (-3200 5225);
DISPLAY INVISIBLE (-3200 5225);
FORCEPROP 1 LASTPIN (-3250 5150) $PN 1
J 0
(-3240 5130);
DISPLAY 0.787234 (-3240 5130);
PAINT MONO (-3240 5130);
FORCEPROP 1 LASTPIN (-3250 4950) $PN 2
J 0
(-3240 4930);
DISPLAY 0.787234 (-3240 4930);
PAINT MONO (-3240 4930);
FORCEPROP 1 LAST VALUE 0.1UF
J 0
(-3200 5150);
DISPLAY 0.489362 (-3200 5150);
PAINT SKYBLUE (-3200 5150);
FORCEPROP 1 LAST VOLTAGE 25V
J 0
(-3200 5100);
DISPLAY 0.489362 (-3200 5100);
PAINT SKYBLUE (-3200 5100);
FORCEPROP 1 LAST PACK_TYPE 0402
J 0
(-3200 4950);
DISPLAY 0.489362 (-3200 4950);
PAINT SKYBLUE (-3200 4950);
FORCEPROP 1 LAST MATERIAL X7R
J 0
(-3200 5000);
DISPLAY 0.489362 (-3200 5000);
PAINT SKYBLUE (-3200 5000);
FORCEPROP 1 LAST TOLERANCE 10%
J 0
(-3200 5050);
DISPLAY 0.489362 (-3200 5050);
PAINT SKYBLUE (-3200 5050);
FORCEPROP 2 LAST CDS_LIB pure_quanta
J 0
(-3250 5050);
DISPLAY INVISIBLE (-3250 5050);
FORCEPROP 1 LAST PATH I87
J 0
(-3200 5200);
DISPLAY 0.978723 (-3200 5200);
PAINT WHITE (-3200 5200);
DISPLAY INVISIBLE (-3200 5200);
FORCEPROP 1 LAST PART_NUMBER CH4104K1B00
J 0
(-3200 4900);
DISPLAY 0.489362 (-3200 4900);
PAINT SKYBLUE (-3200 4900);
DISPLAY INVISIBLE (-3200 4900);
FORCEADD VCC_CORE..1
(-3250 5375);
FORCEPROP 3 LASTPIN (-3250 5325) SIG_NAME P12V_AUX\g
J 0
(-3240 5335);
DISPLAY 0.659574 (-3240 5335);
PAINT MONO (-3240 5335);
DISPLAY INVISIBLE (-3240 5335);
FORCEPROP 1 LAST HDL_POWER P12V_AUX
J 1
(-3250 5425);
DISPLAY 0.489362 (-3250 5425);
PAINT GREEN (-3250 5425);
FORCEPROP 2 LAST CDS_LIB pure_quanta_power
J 0
(-3250 5375);
DISPLAY INVISIBLE (-3250 5375);
FORCEPROP 1 LAST PATH I88
J 0
(-3200 5400);
DISPLAY 0.872340 (-3200 5400);
PAINT AQUA (-3200 5400);
DISPLAY INVISIBLE (-3200 5400);
FORCEADD Q_CAP..1
(-2150 3925);
FORCEPROP 1 LAST LOCATION PC105_1
J 0
(-2100 4050);
DISPLAY 0.489362 (-2100 4050);
PAINT SKYBLUE (-2100 4050);
FORCEPROP 0 LAST $SEC 1
J 0
(-2100 4100);
DISPLAY 0.680851 (-2100 4100);
PAINT MONO (-2100 4100);
DISPLAY INVISIBLE (-2100 4100);
FORCEPROP 0 LAST CDS_SEC 1
J 0
(-2100 4100);
DISPLAY 1.021277 (-2100 4100);
DISPLAY INVISIBLE (-2100 4100);
FORCEPROP 1 LASTPIN (-2150 4025) $PN 1
J 0
(-2140 4005);
DISPLAY 0.489362 (-2140 4005);
PAINT MONO (-2140 4005);
FORCEPROP 1 LASTPIN (-2150 3825) $PN 2
J 0
(-2140 3805);
DISPLAY 0.489362 (-2140 3805);
PAINT MONO (-2140 3805);
FORCEPROP 1 LAST PACK_TYPE C0805
J 0
(-2100 3800);
DISPLAY 0.489362 (-2100 3800);
PAINT SKYBLUE (-2100 3800);
FORCEPROP 1 LAST TOLERANCE 20%
J 0
(-2100 3900);
DISPLAY 0.489362 (-2100 3900);
PAINT SKYBLUE (-2100 3900);
FORCEPROP 1 LAST VALUE 22UF
J 0
(-2100 4000);
DISPLAY 0.489362 (-2100 4000);
PAINT SKYBLUE (-2100 4000);
FORCEPROP 1 LAST VOLTAGE 4V
J 0
(-2100 3950);
DISPLAY 0.489362 (-2100 3950);
PAINT SKYBLUE (-2100 3950);
FORCEPROP 1 LAST MATERIAL X6S
J 0
(-2100 3850);
DISPLAY 0.489362 (-2100 3850);
PAINT SKYBLUE (-2100 3850);
FORCEPROP 2 LAST CDS_LIB pure_quanta
J 0
(-2150 3925);
DISPLAY INVISIBLE (-2150 3925);
FORCEPROP 1 LAST PATH I89
J 0
(-2100 4075);
DISPLAY 0.978723 (-2100 4075);
PAINT WHITE (-2100 4075);
DISPLAY INVISIBLE (-2100 4075);
FORCEPROP 1 LAST PART_NUMBER CH622KMEA03
J 0
(-2100 3750);
DISPLAY 0.489362 (-2100 3750);
PAINT SKYBLUE (-2100 3750);
DISPLAY INVISIBLE (-2100 3750);
FORCEADD UNIVERSAL_GND..1
(-8875 1400);
FORCEPROP 3 LASTPIN (-8875 1450) SIG_NAME GND\g
J 0
(-8865 1460);
DISPLAY 0.659574 (-8865 1460);
PAINT MONO (-8865 1460);
DISPLAY INVISIBLE (-8865 1460);
FORCEPROP 2 LAST CDS_LIB pure_quanta_power
J 0
(-8875 1400);
DISPLAY INVISIBLE (-8875 1400);
FORCEPROP 1 LAST HDL_POWER GND
J 1
(-8850 1325);
DISPLAY 0.872340 (-8850 1325);
PAINT GREEN (-8850 1325);
DISPLAY INVISIBLE (-8850 1325);
FORCEPROP 1 LAST PATH I9
J 0
(-8800 1400);
DISPLAY 0.872340 (-8800 1400);
PAINT AQUA (-8800 1400);
DISPLAY INVISIBLE (-8800 1400);
FORCEADD Q_RES..2
(-1850 3900);
FORCEPROP 1 LAST LOCATION PR444
J 0
(-1795 4050);
DISPLAY 0.489362 (-1795 4050);
PAINT SKYBLUE (-1795 4050);
FORCEPROP 0 LAST $SEC 1
J 0
(-1775 4075);
DISPLAY 0.680851 (-1775 4075);
PAINT MONO (-1775 4075);
DISPLAY INVISIBLE (-1775 4075);
FORCEPROP 0 LAST CDS_SEC 1
J 0
(-1775 4075);
DISPLAY 1.021277 (-1775 4075);
DISPLAY INVISIBLE (-1775 4075);
FORCEPROP 1 LASTPIN (-1850 4000) $PN 1
J 0
(-1845 3962);
DISPLAY 0.787234 (-1845 3962);
PAINT MONO (-1845 3962);
DISPLAY INVISIBLE (-1845 3962);
FORCEPROP 1 LASTPIN (-1850 3800) $PN 2
J 0
(-1845 3810);
DISPLAY 0.787234 (-1845 3810);
PAINT MONO (-1845 3810);
DISPLAY INVISIBLE (-1845 3810);
FORCEPROP 1 LAST WATTAGE 1/16W
J 0
(-1800 3900);
DISPLAY 0.489362 (-1800 3900);
PAINT SKYBLUE (-1800 3900);
FORCEPROP 1 LAST MATERIAL CHIP
J 0
(-1800 3850);
DISPLAY 0.489362 (-1800 3850);
PAINT SKYBLUE (-1800 3850);
FORCEPROP 1 LAST TOLERANCE 1%
J 0
(-1795 3950);
DISPLAY 0.489362 (-1795 3950);
PAINT SKYBLUE (-1795 3950);
FORCEPROP 1 LAST VALUE 1K
J 0
(-1795 4000);
DISPLAY 0.489362 (-1795 4000);
PAINT SKYBLUE (-1795 4000);
FORCEPROP 1 LAST PACK_TYPE 0402LF
J 0
(-1800 3750);
DISPLAY 0.489362 (-1800 3750);
PAINT SKYBLUE (-1800 3750);
FORCEPROP 2 LAST CDS_LIB pure_quanta
J 0
(-1850 3900);
DISPLAY INVISIBLE (-1850 3900);
FORCEPROP 1 LAST PATH I90
J 0
(-1800 4075);
DISPLAY 0.978723 (-1800 4075);
PAINT WHITE (-1800 4075);
DISPLAY INVISIBLE (-1800 4075);
FORCEPROP 1 LAST PART_NUMBER CS21002FB06
J 0
(-1800 3800);
DISPLAY 0.489362 (-1800 3800);
PAINT SKYBLUE (-1800 3800);
DISPLAY INVISIBLE (-1800 3800);
FORCEADD VCC_CORE..1
(-1850 4250);
FORCEPROP 3 LASTPIN (-1850 4200) SIG_NAME PVDDCR_CPU1_P0\g
J 0
(-1840 4210);
DISPLAY 0.659574 (-1840 4210);
PAINT MONO (-1840 4210);
DISPLAY INVISIBLE (-1840 4210);
FORCEPROP 1 LAST HDL_POWER PVDDCR_CPU1_P0
J 1
(-1850 4300);
DISPLAY 0.489362 (-1850 4300);
PAINT GREEN (-1850 4300);
FORCEPROP 2 LAST CDS_LIB pure_quanta_power
J 0
(-1850 4250);
DISPLAY INVISIBLE (-1850 4250);
FORCEPROP 1 LAST PATH I91
J 0
(-1800 4275);
DISPLAY 0.872340 (-1800 4275);
PAINT AQUA (-1800 4275);
DISPLAY INVISIBLE (-1800 4275);
FORCEADD DNS..1
(-5900 3500);
PAINT RED (-5900 3500);
FORCEPROP 2 LAST CDS_LIB mstr_misc
J 0
(-5900 3500);
DISPLAY INVISIBLE (-5900 3500);
FORCEPROP 1 LAST COMMENT_BODY TRUE
R 1
J 0
(-5825 3275);
DISPLAY 0.872340 (-5825 3275);
PAINT GREEN (-5825 3275);
DISPLAY INVISIBLE (-5825 3275);
FORCEADD DNS..1
(-5900 3950);
PAINT RED (-5900 3950);
FORCEPROP 2 LAST CDS_LIB mstr_misc
J 0
(-5900 3950);
DISPLAY INVISIBLE (-5900 3950);
FORCEPROP 1 LAST COMMENT_BODY TRUE
R 1
J 0
(-5825 3725);
DISPLAY 0.872340 (-5825 3725);
PAINT GREEN (-5825 3725);
DISPLAY INVISIBLE (-5825 3725);
FORCEADD DNS..1
(-5900 550);
PAINT RED (-5900 550);
FORCEPROP 2 LAST CDS_LIB mstr_misc
J 0
(-5900 550);
DISPLAY INVISIBLE (-5900 550);
FORCEPROP 1 LAST COMMENT_BODY TRUE
R 1
J 0
(-5825 325);
DISPLAY 0.872340 (-5825 325);
PAINT GREEN (-5825 325);
DISPLAY INVISIBLE (-5825 325);
FORCEADD DNS..1
(-9150 650);
PAINT RED (-9150 650);
FORCEPROP 2 LAST CDS_LIB mstr_misc
J 0
(-9150 650);
PAINT MONO (-9150 650);
DISPLAY INVISIBLE (-9150 650);
FORCEPROP 1 LAST COMMENT_BODY TRUE
R 1
J 0
(-9075 425);
DISPLAY 0.872340 (-9075 425);
PAINT GREEN (-9075 425);
DISPLAY INVISIBLE (-9075 425);
FORCEADD DNS..1
(-9250 5450);
PAINT RED (-9250 5450);
FORCEPROP 2 LAST CDS_LIB mstr_misc
J 0
(-9250 5450);
DISPLAY INVISIBLE (-9250 5450);
FORCEPROP 1 LAST COMMENT_BODY TRUE
R 1
J 0
(-9175 5225);
DISPLAY 0.872340 (-9175 5225);
PAINT GREEN (-9175 5225);
DISPLAY INVISIBLE (-9175 5225);
FORCEADD DNS..1
(-5875 975);
PAINT RED (-5875 975);
FORCEPROP 2 LAST CDS_LIB mstr_misc
J 0
(-5875 975);
DISPLAY INVISIBLE (-5875 975);
FORCEPROP 1 LAST COMMENT_BODY TRUE
R 1
J 0
(-5800 750);
DISPLAY 0.872340 (-5800 750);
PAINT GREEN (-5800 750);
DISPLAY INVISIBLE (-5800 750);
FORCEADD DNS..1
(-9125 3600);
PAINT RED (-9125 3600);
FORCEPROP 2 LAST CDS_LIB mstr_misc
J 0
(-9125 3600);
PAINT MONO (-9125 3600);
DISPLAY INVISIBLE (-9125 3600);
FORCEPROP 1 LAST COMMENT_BODY TRUE
R 1
J 0
(-9050 3375);
DISPLAY 0.872340 (-9050 3375);
PAINT GREEN (-9050 3375);
DISPLAY INVISIBLE (-9050 3375);
FORCEADD QUANTA_TITLE_BLOCK_C..1
(-825 -325);
FORCEPROP 0 LAST CDS_CON_LAST_MODIFIED Thu Sep 14 16:12:18 2023
J 0
(-2710 -310);
DISPLAY INVISIBLE (-2710 -310);
FORCEPROP 1 LAST CUSTOM_TXT_CDS <CON_LAST_MODIFIED>
J 0
(-2710 -310);
DISPLAY 0.978723 (-2710 -310);
FORCEPROP 2 LAST CUSTOM_TXT_CDS <XR_PAGE_TITLE>
J 0
(-8715 4925);
DISPLAY 0.638298 (-8715 4925);
PAINT PINK (-8715 4925);
DISPLAY INVISIBLE (-8715 4925);
FORCEPROP 1 LAST CUSTOM_TXT_CDS <NAME_2>
J 0
(-4000 -275);
FORCEPROP 1 LAST CUSTOM_TXT_CDS <NAME_1>
J 0
(-4000 -150);
FORCEPROP 1 LAST CUSTOM_TXT_CDS <Q_NUMBER>
J 0
(-2228 -222);
DISPLAY 1.212766 (-2228 -222);
FORCEPROP 1 LAST CUSTOM_TXT_CDS <Q_PROJ>
J 0
(-3207 -223);
DISPLAY 1.212766 (-3207 -223);
FORCEPROP 1 LAST CUSTOM_TXT_CDS <Q_REV>
J 0
(-1009 -222);
DISPLAY 1.212766 (-1009 -222);
FORCEPROP 1 LAST CUSTOM_TXT_CDS <CON_PAGE_NUM> OF <CON_TOTAL_PAGES>
J 0
(-1271 -307);
DISPLAY 0.978723 (-1271 -307);
FORCEPROP 1 LAST Q_TITLE PVDDCR_CPU1_P0 VR PHASE 1&2
J 0
(-10100 -275);
DISPLAY 2.446809 (-10100 -275);
PAINT GREEN (-10100 -275);
FORCEPROP 2 LAST PAGE_BORDER TRUE
J 0
(-8715 4925);
DISPLAY 0.638298 (-8715 4925);
PAINT PINK (-8715 4925);
DISPLAY INVISIBLE (-8715 4925);
FORCEPROP 1 LAST CDS_LMAN_SYM_OUTLINE -9475,6775,100,-125
J 0
(-825 -325);
DISPLAY 0.468085 (-825 -325);
PAINT GREEN (-825 -325);
DISPLAY INVISIBLE (-825 -325);
FORCEPROP 2 LAST CDS_LIB pure_quanta
J 0
(-825 -325);
DISPLAY INVISIBLE (-825 -325);
FORCEPROP 2 LAST CDS_XR_PAGE_TITLE CR-201 : @T6G_MB_LIB.T6G(SCH_1):PAGE201
J 0
(-8715 4925);
DISPLAY 0.638298 (-8715 4925);
PAINT PINK (-8715 4925);
DISPLAY INVISIBLE (-8715 4925);
FORCEPROP 1 LAST Q_DEPT BU9
J 1
(-4588 -276);
DISPLAY 1.957447 (-4588 -276);
PAINT GREEN (-4588 -276);
DISPLAY INVISIBLE (-4588 -276);
FORCEPROP 1 LAST COMMENT_BODY TRUE
J 0
(-813 -338);
DISPLAY 0.978723 (-813 -338);
PAINT GREEN (-813 -338);
DISPLAY INVISIBLE (-813 -338);
WIRE 16 -1 (-9750 750)(-9750 625);
WIRE 16 -1 (-9625 3600)(-9625 3650);
WIRE 16 -1 (-8525 2075)(-8525 1950);
WIRE 16 -1 (-9125 3525)(-9125 3450);
WIRE 16 -1 (-9625 5600)(-9625 5550);
WIRE 16 -1 (-8975 4475)(-8975 4425);
WIRE 16 -1 (-9275 5600)(-9275 5550);
WIRE 16 -1 (-9150 575)(-9150 500);
WIRE 16 -1 (-8625 4875)(-8625 4975);
WIRE 16 -1 (-5875 450)(-5875 375);
WIRE 16 -1 (-5875 3400)(-5875 3325);
WIRE 16 -1 (-3250 4950)(-3250 4775);
WIRE 16 -1 (-3525 5275)(-3250 5275);
WIRE 16 -1 (-3250 5275)(-3250 5150);
WIRE 16 -1 (-3250 5275)(-3250 5325);
WIRE 16 -1 (-8875 1500)(-8875 1450);
WIRE 16 -1 (-5225 4225)(-5225 4250);
WIRE 16 -1 (-6800 4225)(-5225 4225);
FORCEPROP 2 LAST SIG_NAME SW_PVDDCR_CPU1_P0_BOOTR1
J 0
(-6610 4235);
DISPLAY 0.489362 (-6610 4235);
FORCEPROP 2 LASTPROP $XRERR UNIQUE?
J 0
(-6850 4235);
DISPLAY 0.638298 (-6850 4235);
PAINT MONO (-6850 4235);
DISPLAY INVISIBLE (-6850 4235);
WIRE 16 -1 (-5225 4475)(-5225 4450);
WIRE 16 -1 (-5850 4475)(-5225 4475);
FORCEPROP 2 LAST SIG_NAME SW_PVDDCR_CPU1_P0_BOOT1_R
J 0
(-5860 4485);
DISPLAY 0.489362 (-5860 4485);
FORCEPROP 2 LASTPROP $XRERR UNIQUE?
J 0
(-6100 4485);
DISPLAY 0.638298 (-6100 4485);
PAINT MONO (-6100 4485);
DISPLAY INVISIBLE (-6100 4485);
WIRE 16 -1 (-6425 4925)(-6425 4775);
WIRE 16 -1 (-6425 4775)(-6025 4775);
WIRE 16 -1 (-5625 4775)(-6025 4775);
WIRE 16 -1 (-6025 4925)(-6025 4775);
WIRE 16 -1 (-5225 4775)(-5625 4775);
WIRE 16 -1 (-5625 4925)(-5625 4775);
WIRE 16 -1 (-4850 4775)(-5225 4775);
WIRE 16 -1 (-5225 4925)(-5225 4775);
WIRE 16 -1 (-4850 4925)(-4850 4775);
WIRE 16 -1 (-4625 4775)(-4850 4775);
WIRE 16 -1 (-4625 4775)(-4425 4775);
WIRE 16 -1 (-4625 4700)(-4625 4775);
WIRE 16 -1 (-4425 4775)(-4025 4775);
WIRE 16 -1 (-4425 4925)(-4425 4775);
WIRE 16 -1 (-4025 4925)(-4025 4775);
WIRE 16 -1 (-4825 1975)(-4825 1825);
WIRE 16 -1 (-4825 1750)(-4825 1825);
WIRE 16 -1 (-5200 1825)(-4825 1825);
WIRE 16 -1 (-5200 1975)(-5200 1825);
WIRE 16 -1 (-5600 1825)(-5200 1825);
WIRE 16 -1 (-5600 1975)(-5600 1825);
WIRE 16 -1 (-5600 1825)(-6000 1825);
WIRE 16 -1 (-6000 1975)(-6000 1825);
WIRE 16 -1 (-6400 1825)(-6000 1825);
WIRE 16 -1 (-6400 1975)(-6400 1825);
WIRE 16 -1 (-6825 1775)(-6650 1775);
WIRE 16 -1 (-6650 1775)(-6650 1825);
WIRE 16 -1 (-6650 2325)(-6650 1825);
WIRE 16 -1 (-6825 1825)(-6650 1825);
WIRE 16 -1 (-6650 2325)(-6400 2325);
WIRE 16 -1 (-6400 2325)(-6000 2325);
WIRE 16 -1 (-6400 2175)(-6400 2325);
WIRE 16 -1 (-6000 2325)(-5600 2325);
WIRE 16 -1 (-6000 2175)(-6000 2325);
WIRE 16 -1 (-5600 2325)(-5200 2325);
WIRE 16 -1 (-5600 2325)(-5600 2175);
WIRE 16 -1 (-5200 2325)(-4825 2325);
WIRE 16 -1 (-5200 2175)(-5200 2325);
WIRE 16 -1 (-4825 2375)(-4825 2325);
WIRE 16 -1 (-4825 2175)(-4825 2325);
WIRE 16 -1 (-6800 3875)(-6125 3875);
WIRE 16 -1 (-6125 3875)(-6125 3225);
WIRE 16 -1 (-4950 3225)(-6125 3225);
FORCEPROP 2 LAST SIG_NAME PVDDCR_CPU1_P0_VOS1
J 0
(-6735 3900);
DISPLAY 0.489362 (-6735 3900);
FORCEPROP 2 LASTPROP $XRERR UNIQUE?
J 0
(-6975 3900);
DISPLAY 0.638298 (-6975 3900);
PAINT MONO (-6975 3900);
DISPLAY INVISIBLE (-6975 3900);
WIRE 16 -1 (-5875 4125)(-4850 4125);
WIRE 16 -1 (-6800 4125)(-5875 4125);
FORCEPROP 2 LAST SIG_NAME SW_PVDDCR_CPU1_P0_SW1
J 0
(-6610 4135);
DISPLAY 0.489362 (-6610 4135);
FORCEPROP 2 LASTPROP $XRERR UNIQUE?
J 0
(-6850 4135);
DISPLAY 0.638298 (-6850 4135);
PAINT MONO (-6850 4135);
DISPLAY INVISIBLE (-6850 4135);
WIRE 16 -1 (-5875 4125)(-5875 4050);
WIRE 16 -1 (-4025 5125)(-4025 5275);
WIRE 16 -1 (-3725 5275)(-4025 5275);
WIRE 16 -1 (-4425 5275)(-4025 5275);
WIRE 16 -1 (-4425 5275)(-4425 5125);
WIRE 16 -1 (-4625 5275)(-4425 5275);
WIRE 16 -1 (-4625 5325)(-4625 5275);
WIRE 16 -1 (-4625 5275)(-4850 5275);
WIRE 16 -1 (-4850 5125)(-4850 5275);
WIRE 16 -1 (-4850 5275)(-5225 5275);
WIRE 16 -1 (-5225 5125)(-5225 5275);
WIRE 16 -1 (-5225 5275)(-5625 5275);
WIRE 16 -1 (-5625 5275)(-5625 5125);
WIRE 16 -1 (-5625 5275)(-6025 5275);
WIRE 16 -1 (-6025 5125)(-6025 5275);
WIRE 16 -1 (-6425 5275)(-6025 5275);
WIRE 16 -1 (-6425 5125)(-6425 5275);
WIRE 16 -1 (-6625 5275)(-6425 5275);
WIRE 16 -1 (-6625 5275)(-6625 4775);
WIRE 16 -1 (-6625 4725)(-6625 4775);
WIRE 16 -1 (-6800 4775)(-6625 4775);
WIRE 16 -1 (-6800 4725)(-6625 4725);
WIRE 16 -1 (-6800 4475)(-6050 4475);
FORCEPROP 2 LAST SIG_NAME SW_PVDDCR_CPU1_P0_BOOT1
J 0
(-6635 4485);
DISPLAY 0.489362 (-6635 4485);
FORCEPROP 2 LASTPROP $XRERR UNIQUE?
J 0
(-6875 4485);
DISPLAY 0.638298 (-6875 4485);
PAINT MONO (-6875 4485);
DISPLAY INVISIBLE (-6875 4485);
WIRE 16 -1 (-6825 1525)(-6075 1525);
FORCEPROP 2 LAST SIG_NAME SW_PVDDCR_CPU1_P0_BOOT2
J 0
(-6685 1535);
DISPLAY 0.489362 (-6685 1535);
FORCEPROP 2 LASTPROP $XRERR UNIQUE?
J 0
(-6925 1535);
DISPLAY 0.638298 (-6925 1535);
PAINT MONO (-6925 1535);
DISPLAY INVISIBLE (-6925 1535);
WIRE 16 -1 (-5175 1525)(-5175 1500);
WIRE 16 -1 (-5875 1525)(-5175 1525);
FORCEPROP 2 LAST SIG_NAME SW_PVDDCR_CPU1_P0_BOOT2_R
J 0
(-5810 1535);
DISPLAY 0.489362 (-5810 1535);
FORCEPROP 2 LASTPROP $XRERR UNIQUE?
J 0
(-6050 1535);
DISPLAY 0.638298 (-6050 1535);
PAINT MONO (-6050 1535);
DISPLAY INVISIBLE (-6050 1535);
WIRE 16 -1 (-6800 3825)(-6275 3825);
FORCEPROP 2 LAST SIG_NAME NC_PVDDCR_CPU1_P0_GL1_1
J 0
(-6735 3835);
DISPLAY 0.489362 (-6735 3835);
FORCEPROP 2 LASTPROP $XRERR UNIQUE?
J 0
(-6245 3825);
DISPLAY 0.638298 (-6245 3825);
PAINT MONO (-6245 3825);
DISPLAY INVISIBLE (-6245 3825);
WIRE 16 -1 (-9125 3825)(-7650 3825);
FORCEPROP 2 LAST SIG_NAME PVDDCR_CPU1_P0_LSET1
J 0
(-8460 3835);
DISPLAY 0.489362 (-8460 3835);
FORCEPROP 2 LASTPROP $XRERR UNIQUE?
J 0
(-8700 3835);
DISPLAY 0.638298 (-8700 3835);
PAINT MONO (-8700 3835);
DISPLAY INVISIBLE (-8700 3835);
WIRE 16 -1 (-9125 3825)(-9125 3725);
WIRE 16 -1 (-7650 3625)(-8500 3625);
FORCEPROP 2 LAST SIG_NAME PVDDCR_CPU1_P0_TEMP0
J 0
(-8460 3635);
DISPLAY 0.489362 (-8460 3635);
WIRE 16 -1 (-8200 2375)(-8525 2375);
WIRE 16 -1 (-8200 1825)(-8200 2375);
WIRE 16 -1 (-8525 2275)(-8525 2375);
WIRE 16 -1 (-8525 2375)(-8875 2375);
WIRE 16 -1 (-8875 2250)(-8875 2375);
WIRE 16 -1 (-8875 2375)(-8875 2525);
WIRE 16 -1 (-7675 1825)(-8200 1825);
WIRE 16 -1 (-9625 5350)(-9625 5275);
WIRE 16 -1 (-9275 5275)(-9625 5275);
WIRE 16 -1 (-8975 5275)(-9275 5275);
WIRE 16 -1 (-9275 5350)(-9275 5275);
WIRE 16 -1 (-8975 5275)(-8775 5275);
WIRE 16 -1 (-8975 5150)(-8975 5275);
WIRE 16 -1 (-8625 5275)(-8775 5275);
WIRE 16 -1 (-8775 5600)(-8775 5275);
WIRE 16 -1 (-7725 5275)(-8625 5275);
WIRE 16 -1 (-8625 5275)(-8625 5175);
WIRE 16 -1 (-7725 4775)(-7725 5275);
WIRE 16 -1 (-7650 4775)(-7725 4775);
WIRE 16 -1 (-6825 625)(-6575 625);
WIRE 16 -1 (-6575 675)(-6575 625);
WIRE 16 -1 (-6575 625)(-6575 575);
WIRE 16 -1 (-6825 575)(-6575 575);
WIRE 16 -1 (-6575 575)(-6575 500);
WIRE 16 -1 (-6575 725)(-6575 675);
WIRE 16 -1 (-6825 675)(-6575 675);
WIRE 16 -1 (-6825 725)(-6575 725);
WIRE 16 -1 (-6800 3575)(-6550 3575);
WIRE 16 -1 (-6550 3625)(-6550 3575);
WIRE 16 -1 (-6550 3575)(-6550 3525);
WIRE 16 -1 (-6800 3525)(-6550 3525);
WIRE 16 -1 (-6550 3525)(-6550 3450);
WIRE 16 -1 (-6550 3675)(-6550 3625);
WIRE 16 -1 (-6800 3625)(-6550 3625);
WIRE 16 -1 (-6800 3675)(-6550 3675);
WIRE 16 -1 (-2400 2575)(-2400 2425);
WIRE 16 -1 (-2400 2350)(-2400 2425);
WIRE 16 -1 (-2400 2425)(-2700 2425);
WIRE 16 -1 (-2700 2425)(-2700 2575);
WIRE 16 -1 (-3025 2425)(-2700 2425);
WIRE 16 -1 (-3025 2575)(-3025 2425);
WIRE 16 -1 (-3350 2425)(-3025 2425);
WIRE 16 -1 (-3350 2575)(-3350 2425);
WIRE 16 -1 (-3700 2425)(-3350 2425);
WIRE 16 -1 (-3700 2575)(-3700 2425);
WIRE 16 -1 (-2400 2775)(-2400 2875);
WIRE 16 -1 (-2400 2925)(-2400 2875);
WIRE 16 -1 (-2400 2875)(-2700 2875);
WIRE 16 -1 (-2700 2775)(-2700 2875);
WIRE 16 -1 (-3025 2875)(-2700 2875);
WIRE 16 -1 (-3025 2775)(-3025 2875);
WIRE 16 -1 (-3350 2875)(-3025 2875);
WIRE 16 -1 (-3350 2775)(-3350 2875);
WIRE 16 -1 (-3700 2875)(-3350 2875);
WIRE 16 -1 (-3700 2775)(-3700 2875);
WIRE 16 -1 (-2300 750)(-2300 875);
WIRE 16 -1 (-2300 675)(-2300 750);
WIRE 16 -1 (-2300 750)(-2725 750);
WIRE 16 -1 (-2725 750)(-2725 875);
WIRE 16 -1 (-2300 1175)(-2300 1075);
WIRE 16 -1 (-2300 1225)(-2300 1175);
WIRE 16 -1 (-2725 1175)(-2300 1175);
WIRE 16 -1 (-2725 1175)(-2725 1075);
WIRE 16 -1 (-2725 1175)(-3050 1175);
WIRE 16 -1 (-3050 1175)(-3050 275);
WIRE 16 -1 (-3750 1175)(-3050 1175);
WIRE 16 -1 (-4825 275)(-3050 275);
WIRE 16 -1 (-1850 3800)(-1850 3700);
WIRE 16 -1 (-1850 3625)(-1850 3700);
WIRE 16 -1 (-1850 3700)(-2150 3700);
WIRE 16 -1 (-2150 3825)(-2150 3700);
WIRE 16 -1 (-2150 3700)(-2575 3700);
WIRE 16 -1 (-2575 3700)(-2575 3825);
WIRE 16 -1 (-2975 3700)(-2575 3700);
WIRE 16 -1 (-2975 3825)(-2975 3700);
WIRE 16 -1 (-1850 4200)(-1850 4125);
WIRE 16 -1 (-1850 4125)(-2150 4125);
WIRE 16 -1 (-1850 4125)(-1850 4000);
WIRE 16 -1 (-2575 4125)(-2150 4125);
WIRE 16 -1 (-2150 4025)(-2150 4125);
WIRE 16 -1 (-2975 4125)(-2575 4125);
WIRE 16 -1 (-2575 4125)(-2575 4025);
WIRE 16 -1 (-2975 4125)(-3175 4125);
WIRE 16 -1 (-2975 4025)(-2975 4125);
WIRE 16 -1 (-4050 4125)(-3175 4125);
WIRE 16 -1 (-3175 4125)(-3175 3225);
WIRE 16 -1 (-3175 3225)(-4750 3225);
WIRE 16 -1 (-9150 875)(-7675 875);
FORCEPROP 2 LAST SIG_NAME PVDDCR_CPU1_P0_LSET2
J 0
(-8510 885);
DISPLAY 0.489362 (-8510 885);
FORCEPROP 2 LASTPROP $XRERR UNIQUE?
J 0
(-8750 885);
DISPLAY 0.638298 (-8750 885);
PAINT MONO (-8750 885);
DISPLAY INVISIBLE (-8750 885);
WIRE 16 -1 (-9150 875)(-9150 775);
WIRE 16 -1 (-7750 4025)(-7750 3950);
FORCEPROP 0 LAST CDS_PHYS_NET_NAME PVDDCR_CPU1_P0_VCCS
J 0
(-7750 3975);
PAINT MONO (-7750 3975);
DISPLAY INVISIBLE (-7750 3975);
WIRE 16 -1 (-7750 4025)(-7650 4025);
WIRE 16 -1 (-8500 4025)(-7750 4025);
FORCEPROP 2 LAST SIG_NAME PVDDCR_CPU1_P0_VCCS
J 0
(-8460 4035);
DISPLAY 0.489362 (-8460 4035);
WIRE 16 -1 (-7750 3950)(-9625 3950);
WIRE 16 -1 (-9625 3950)(-9625 3850);
WIRE 16 -1 (-7675 1175)(-8550 1175);
FORCEPROP 2 LAST SIG_NAME PVDDCR_CPU1_P0_IMON2
J 0
(-8510 1185);
DISPLAY 0.489362 (-8510 1185);
WIRE 16 -1 (-8550 1075)(-7775 1075);
FORCEPROP 2 LAST SIG_NAME PVDDCR_CPU1_P0_VCCS
J 0
(-8510 1085);
DISPLAY 0.489362 (-8510 1085);
WIRE 16 -1 (-7775 1075)(-7675 1075);
WIRE 16 -1 (-7775 1075)(-7775 1000);
FORCEPROP 0 LAST CDS_PHYS_NET_NAME PVDDCR_CPU1_P0_VCCS
J 0
(-7775 1025);
PAINT MONO (-7775 1025);
DISPLAY INVISIBLE (-7775 1025);
WIRE 16 -1 (-9750 1000)(-7775 1000);
WIRE 16 -1 (-9750 1000)(-9750 950);
WIRE 16 -1 (-7675 575)(-8550 575);
FORCEPROP 2 LAST SIG_NAME PVDDCR_CPU1_P0_PWM2
J 0
(-8510 585);
DISPLAY 0.489362 (-8510 585);
WIRE 16 -1 (-7675 675)(-8550 675);
FORCEPROP 2 LAST SIG_NAME PVDDCR_CPU1_P0_TEMP0
J 0
(-8510 685);
DISPLAY 0.489362 (-8510 685);
WIRE 16 -1 (-7650 4125)(-8500 4125);
FORCEPROP 2 LAST SIG_NAME PVDDCR_CPU1_P0_IMON1
J 0
(-8460 4135);
DISPLAY 0.489362 (-8460 4135);
WIRE 16 -1 (-7650 3525)(-8500 3525);
FORCEPROP 2 LAST SIG_NAME PVDDCR_CPU1_P0_PWM1
J 0
(-8460 3535);
DISPLAY 0.489362 (-8460 3535);
WIRE 16 -1 (-7675 925)(-8050 925);
FORCEPROP 2 LAST SIG_NAME NC_PVDDCR_CPU1_P0_DNC2
J 0
(-8245 935);
DISPLAY 0.489362 (-8245 935);
FORCEPROP 2 LASTPROP $XRERR UNIQUE?
J 0
(-8290 925);
DISPLAY 0.638298 (-8290 925);
PAINT MONO (-8290 925);
DISPLAY INVISIBLE (-8290 925);
WIRE 16 -1 (-7675 1325)(-7775 1325);
WIRE 16 -1 (-7775 1325)(-7775 1525);
WIRE 16 -1 (-7675 1525)(-7775 1525);
WIRE 16 -1 (-7775 1525)(-8300 1525);
FORCEPROP 2 LAST SIG_NAME PVDDCR_CPU1_P0_VCC2
J 0
(-8260 1535);
DISPLAY 0.489362 (-8260 1535);
FORCEPROP 2 LASTPROP $XRERR UNIQUE?
J 0
(-8500 1535);
DISPLAY 0.638298 (-8500 1535);
PAINT MONO (-8500 1535);
DISPLAY INVISIBLE (-8500 1535);
WIRE 16 -1 (-8300 1525)(-8300 1775);
WIRE 16 -1 (-8875 1775)(-8300 1775);
WIRE 16 -1 (-8875 2050)(-8875 1775);
WIRE 16 -1 (-8875 1775)(-8875 1700);
WIRE 16 -1 (-6825 1275)(-5175 1275);
FORCEPROP 2 LAST SIG_NAME SW_PVDDCR_CPU1_P0_BOOTR2
J 0
(-6635 1285);
DISPLAY 0.489362 (-6635 1285);
FORCEPROP 2 LASTPROP $XRERR UNIQUE?
J 0
(-6875 1285);
DISPLAY 0.638298 (-6875 1285);
PAINT MONO (-6875 1285);
DISPLAY INVISIBLE (-6875 1285);
WIRE 16 -1 (-5175 1275)(-5175 1300);
WIRE 16 -1 (-6825 875)(-6300 875);
FORCEPROP 2 LAST SIG_NAME NC_PVDDCR_CPU1_P0_GL1_2
J 0
(-6760 885);
DISPLAY 0.489362 (-6760 885);
FORCEPROP 2 LASTPROP $XRERR UNIQUE?
J 0
(-6270 875);
DISPLAY 0.638298 (-6270 875);
PAINT MONO (-6270 875);
DISPLAY INVISIBLE (-6270 875);
WIRE 16 -1 (-6300 825)(-6825 825);
FORCEPROP 2 LAST SIG_NAME NC_PVDDCR_CPU1_P0_GL2_2
J 0
(-6760 835);
DISPLAY 0.489362 (-6760 835);
FORCEPROP 2 LASTPROP $XRERR UNIQUE?
J 0
(-6270 825);
DISPLAY 0.638298 (-6270 825);
PAINT MONO (-6270 825);
DISPLAY INVISIBLE (-6270 825);
WIRE 16 -1 (-6825 925)(-6175 925);
FORCEPROP 2 LAST SIG_NAME PVDDCR_CPU1_P0_VOS2
J 0
(-6760 950);
DISPLAY 0.489362 (-6760 950);
FORCEPROP 2 LASTPROP $XRERR UNIQUE?
J 0
(-7000 950);
DISPLAY 0.638298 (-7000 950);
PAINT MONO (-7000 950);
DISPLAY INVISIBLE (-7000 950);
WIRE 16 -1 (-6175 925)(-6175 275);
WIRE 16 -1 (-6175 275)(-5025 275);
WIRE 16 -1 (-5875 900)(-5875 650);
FORCEPROP 2 LAST SIG_NAME SW_PVDDCR_CPU1_P0_SW2_RC
J 0
(-5835 735);
DISPLAY 0.489362 (-5835 735);
FORCEPROP 2 LASTPROP $XRERR UNIQUE?
J 0
(-6075 735);
DISPLAY 0.638298 (-6075 735);
PAINT MONO (-6075 735);
DISPLAY INVISIBLE (-6075 735);
WIRE 16 -1 (-5100 925)(-4550 925);
FORCEPROP 2 LAST SIG_NAME IND_CPU1_P0_CPL1
J 0
(-5035 935);
DISPLAY 0.489362 (-5035 935);
WIRE 16 -1 (-5875 3850)(-5875 3600);
FORCEPROP 2 LAST SIG_NAME SW_PVDDCR_CPU1_P0_SW1_RC
J 0
(-5835 3685);
DISPLAY 0.489362 (-5835 3685);
FORCEPROP 2 LASTPROP $XRERR UNIQUE?
J 0
(-6075 3685);
DISPLAY 0.638298 (-6075 3685);
PAINT MONO (-6075 3685);
DISPLAY INVISIBLE (-6075 3685);
WIRE 16 -1 (-7650 3875)(-8025 3875);
FORCEPROP 2 LAST SIG_NAME NC_PVDDCR_CPU1_P0_DNC1
J 0
(-8220 3885);
DISPLAY 0.489362 (-8220 3885);
FORCEPROP 2 LASTPROP $XRERR UNIQUE?
J 0
(-8265 3875);
DISPLAY 0.638298 (-8265 3875);
PAINT MONO (-8265 3875);
DISPLAY INVISIBLE (-8265 3875);
WIRE 16 -1 (-7650 4275)(-7750 4275);
WIRE 16 -1 (-7750 4275)(-7750 4475);
WIRE 16 -1 (-7750 4475)(-7650 4475);
WIRE 16 -1 (-7750 4475)(-8400 4475);
FORCEPROP 2 LAST SIG_NAME PVDDCR_CPU1_P0_VCC1
J 0
(-8285 4485);
DISPLAY 0.489362 (-8285 4485);
FORCEPROP 2 LASTPROP $XRERR UNIQUE?
J 0
(-8525 4485);
DISPLAY 0.638298 (-8525 4485);
PAINT MONO (-8525 4485);
DISPLAY INVISIBLE (-8525 4485);
WIRE 16 -1 (-8400 4750)(-8400 4475);
WIRE 16 -1 (-8975 4750)(-8400 4750);
WIRE 16 -1 (-8975 4950)(-8975 4750);
WIRE 16 -1 (-8975 4750)(-8975 4675);
WIRE 16 -1 (-6800 3775)(-6275 3775);
FORCEPROP 2 LAST SIG_NAME NC_PVDDCR_CPU1_P0_GL2_1
J 0
(-6735 3785);
DISPLAY 0.489362 (-6735 3785);
FORCEPROP 2 LASTPROP $XRERR UNIQUE?
J 0
(-6245 3775);
DISPLAY 0.638298 (-6245 3775);
PAINT MONO (-6245 3775);
DISPLAY INVISIBLE (-6245 3775);
WIRE 16 -1 (-4850 3875)(-5325 3875);
FORCEPROP 2 LAST SIG_NAME IND_CPU1_P0_CPL5
J 0
(-5335 3885);
DISPLAY 0.489362 (-5335 3885);
WIRE 16 -1 (-3750 925)(-3325 925);
FORCEPROP 2 LAST SIG_NAME IND_CPU1_P0_CPL2
J 0
(-3710 935);
DISPLAY 0.489362 (-3710 935);
WIRE 17 273 (-1875 2075)(-1875 3150);
WIRE 17 273 (-4025 2075)(-1875 2075);
WIRE 17 273 (-1875 3150)(-4025 3150);
WIRE 17 273 (-4025 3150)(-4025 2075);
WIRE 16 -1 (-4050 3875)(-3600 3875);
FORCEPROP 2 LAST SIG_NAME IND_CPU1_P0_CPL1
J 0
(-3960 3885);
DISPLAY 0.489362 (-3960 3885);
WIRE 16 -1 (-6825 1175)(-5875 1175);
FORCEPROP 2 LAST SIG_NAME SW_PVDDCR_CPU1_P0_SW2
J 0
(-6635 1185);
DISPLAY 0.489362 (-6635 1185);
FORCEPROP 2 LASTPROP $XRERR UNIQUE?
J 0
(-6875 1185);
DISPLAY 0.638298 (-6875 1185);
PAINT MONO (-6875 1185);
DISPLAY INVISIBLE (-6875 1185);
WIRE 16 -1 (-4550 1175)(-5875 1175);
WIRE 16 -1 (-5875 1175)(-5875 1100);
DOT 1 (-5600 2325);
DOT 1 (-1850 4125);
DOT 1 (-2150 4125);
DOT 1 (-3250 5275);
DOT 1 (-2575 4125);
DOT 1 (-2975 4125);
DOT 1 (-3175 4125);
DOT 1 (-4025 5275);
DOT 1 (-1850 3700);
DOT 1 (-2150 3700);
DOT 1 (-2300 1175);
DOT 1 (-2300 750);
DOT 1 (-2575 3700);
DOT 1 (-2400 2875);
DOT 1 (-2700 2875);
DOT 1 (-3025 2875);
DOT 1 (-2400 2425);
DOT 1 (-2700 2425);
DOT 1 (-3025 2425);
DOT 1 (-3350 2875);
DOT 1 (-3350 2425);
DOT 1 (-2725 1175);
DOT 1 (-3050 1175);
DOT 1 (-4425 5275);
DOT 1 (-4625 5275);
DOT 1 (-4850 5275);
DOT 1 (-5225 5275);
DOT 1 (-4425 4775);
DOT 1 (-4625 4775);
DOT 1 (-4850 4775);
DOT 1 (-5225 4775);
DOT 1 (-5625 5275);
DOT 1 (-5625 4775);
DOT 1 (-5875 4125);
DOT 1 (-6025 4775);
DOT 1 (-6425 5275);
DOT 1 (-7750 4475);
DOT 1 (-7750 4025);
DOT 1 (-4825 2325);
DOT 1 (-4825 1825);
DOT 1 (-5200 2325);
DOT 1 (-5200 1825);
DOT 1 (-5600 1825);
DOT 1 (-6400 2325);
DOT 1 (-5875 1175);
DOT 1 (-6550 3575);
DOT 1 (-6550 3625);
DOT 1 (-6550 3525);
DOT 1 (-6650 1825);
DOT 1 (-6575 675);
DOT 1 (-6575 625);
DOT 1 (-6575 575);
DOT 1 (-7775 1525);
DOT 1 (-7775 1075);
DOT 1 (-8625 5275);
DOT 1 (-8775 5275);
DOT 1 (-8975 5275);
DOT 1 (-9275 5275);
DOT 1 (-8975 4750);
DOT 1 (-8525 2375);
DOT 1 (-8875 2375);
DOT 1 (-8875 1775);
DOT 1 (-6025 5275);
DOT 1 (-6625 4775);
DOT 1 (-6000 2325);
DOT 1 (-6000 1825);
FORCENOTE
3RD=CVA50^0MZ08
(-3775 4975) 0;
DISPLAY LEFT (-3775 4975);
DISPLAY 0.638298 (-3775 4975);
PAINT WHITE (-3775 4975);
FORCENOTE
2ND=CVA50^0MZ07
(-3775 5025) 0;
DISPLAY LEFT (-3775 5025);
DISPLAY 0.638298 (-3775 5025);
PAINT WHITE (-3775 5025);
FORCENOTE
DCR=0.09M OHM
(-3775 5075) 0;
DISPLAY LEFT (-3775 5075);
DISPLAY 0.638298 (-3775 5075);
PAINT WHITE (-3775 5075);
FORCENOTE
2ND SOURCE:INFENEON BOM
(-2750 5650) 0;
DISPLAY LEFT (-2750 5650);
DISPLAY 0.808511 (-2750 5650);
PAINT WHITE (-2750 5650);
FORCENOTE
PU13,PU2,PU15,PU14,PU16,PU11=AL099390004/ISL99390FRZ-TR5935
(-2750 5825) 0;
DISPLAY LEFT (-2750 5825);
DISPLAY 0.638298 (-2750 5825);
PAINT WHITE (-2750 5825);
FORCENOTE
MAIN SOURCE:RENESAS BOM
(-2750 5900) 0;
DISPLAY LEFT (-2750 5900);
DISPLAY 0.808511 (-2750 5900);
PAINT WHITE (-2750 5900);
FORCENOTE
BOM NOTE
(-2750 6000) 0;
DISPLAY LEFT (-2750 6000);
DISPLAY 1.276596 (-2750 6000);
PAINT WHITE (-2750 6000);
FORCENOTE
PU13,PU2,PU15,PU14,PU16,PU11 = AL021590000/TDA21590
(-2750 5575) 0;
DISPLAY LEFT (-2750 5575);
DISPLAY 0.638298 (-2750 5575);
PAINT WHITE (-2750 5575);
FORCENOTE
PR78,PR77,PR86,PR85,PR93,PR7 = CS00002JB13
(-2750 5475) 0;
DISPLAY LEFT (-2750 5475);
DISPLAY 0.638298 (-2750 5475);
PAINT WHITE (-2750 5475);
FORCENOTE
PC84_1,PC83_2,PC114_3,PC113_4,PC132_5,PC111_6 = EMPTY
(-2750 5375) 0;
DISPLAY LEFT (-2750 5375);
DISPLAY 0.638298 (-2750 5375);
PAINT WHITE (-2750 5375);
FORCENOTE
PU13,PU2,PU15,PU14,PU16,PU11 = AL087000A03/MP87000GMJTH-C11D-Z
(-2750 5100) 0;
DISPLAY LEFT (-2750 5100);
DISPLAY 0.638298 (-2750 5100);
PAINT WHITE (-2750 5100);
FORCENOTE
PR443,PR81,PR82,PR89,PR90,PR95,PR420 = CS00002JB13
(-2750 5050) 0;
DISPLAY LEFT (-2750 5050);
DISPLAY 0.638298 (-2750 5050);
PAINT WHITE (-2750 5050);
FORCENOTE
PR442,PR84,PR83,PR92,PR91,PR96,PR421 = EMPTY
(-2750 5000) 0;
DISPLAY LEFT (-2750 5000);
DISPLAY 0.638298 (-2750 5000);
PAINT WHITE (-2750 5000);
FORCENOTE
PC84_1,PC83_2,PC114_3,PC113_4,PC132_5,PC111_6 = EMPTY
(-2750 4950) 0;
DISPLAY LEFT (-2750 4950);
DISPLAY 0.638298 (-2750 4950);
PAINT WHITE (-2750 4950);
FORCENOTE
PR84,PR83,PR92,PR91,PR96,PR421 = EMPTY
(-2750 5425) 0;
DISPLAY LEFT (-2750 5425);
DISPLAY 0.638298 (-2750 5425);
PAINT WHITE (-2750 5425);
FORCENOTE
3RD SOURCE:MPS BOM
(-2750 5175) 0;
DISPLAY LEFT (-2750 5175);
DISPLAY 0.808511 (-2750 5175);
PAINT WHITE (-2750 5175);
FORCENOTE
IRIPPLE:5.08A
(-4050 4675) 0;
DISPLAY LEFT (-4050 4675);
DISPLAY 0.638298 (-4050 4675);
PAINT WHITE (-4050 4675);
FORCENOTE
PVDDCR_CPU1_P0_PHASE2
(-7725 2500) 0;
DISPLAY LEFT (-7725 2500);
DISPLAY 1.021277 (-7725 2500);
PAINT WHITE (-7725 2500);
FORCENOTE
6.0*6.1*7.0
(-3775 5125) 0;
DISPLAY LEFT (-3775 5125);
DISPLAY 0.638298 (-3775 5125);
PAINT WHITE (-3775 5125);
FORCENOTE
PG2292.500HLT
(-3775 5225) 0;
DISPLAY LEFT (-3775 5225);
DISPLAY 0.638298 (-3775 5225);
PAINT WHITE (-3775 5225);
FORCENOTE
ISAT:70A@100C
(-3775 5175) 0;
DISPLAY LEFT (-3775 5175);
DISPLAY 0.638298 (-3775 5175);
PAINT WHITE (-3775 5175);
FORCENOTE
ESR=10M OHM
(-4050 4725) 0;
DISPLAY LEFT (-4050 4725);
DISPLAY 0.638298 (-4050 4725);
PAINT WHITE (-4050 4725);
FORCENOTE
11.0*7.5*12.5
(-3950 4325) 0;
DISPLAY LEFT (-3950 4325);
DISPLAY 0.638298 (-3950 4325);
PAINT WHITE (-3950 4325);
FORCENOTE
DCR=1-4,0.105M OHM
(-3950 4275) 0;
DISPLAY LEFT (-3950 4275);
DISPLAY 0.638298 (-3950 4275);
PAINT WHITE (-3950 4275);
FORCENOTE
DCR=2-3,0.27M OHM
(-3950 4225) 0;
DISPLAY LEFT (-3950 4225);
DISPLAY 0.638298 (-3950 4225);
PAINT WHITE (-3950 4225);
FORCENOTE
2ND=CV+15^0TZ01
(-3950 4175) 0;
DISPLAY LEFT (-3950 4175);
DISPLAY 0.638298 (-3950 4175);
PAINT WHITE (-3950 4175);
FORCENOTE
6.3*8
(-4050 4625) 0;
DISPLAY LEFT (-4050 4625);
DISPLAY 0.638298 (-4050 4625);
PAINT WHITE (-4050 4625);
FORCENOTE
7.3*4.3*1.9
(-3025 2300) 0;
DISPLAY LEFT (-3025 2300);
DISPLAY 0.638298 (-3025 2300);
PAINT WHITE (-3025 2300);
FORCENOTE
ESR=9M OHM
(-3025 2350) 0;
DISPLAY LEFT (-3025 2350);
DISPLAY 0.638298 (-3025 2350);
PAINT WHITE (-3025 2350);
FORCENOTE
MAIN=CH122KM8801
(-3025 2250) 0;
DISPLAY LEFT (-3025 2250);
DISPLAY 0.638298 (-3025 2250);
PAINT WHITE (-3025 2250);
FORCENOTE
PGL6303.151HLT
(-3700 1500) 0;
DISPLAY LEFT (-3700 1500);
DISPLAY 0.638298 (-3700 1500);
PAINT WHITE (-3700 1500);
FORCENOTE
ISAT:70A@100C
(-3700 1450) 0;
DISPLAY LEFT (-3700 1450);
DISPLAY 0.638298 (-3700 1450);
PAINT WHITE (-3700 1450);
FORCENOTE
11.0*7.5*12.5
(-3700 1400) 0;
DISPLAY LEFT (-3700 1400);
DISPLAY 0.638298 (-3700 1400);
PAINT WHITE (-3700 1400);
FORCENOTE
DCR=1-4,0.105M OHM
(-3700 1350) 0;
DISPLAY LEFT (-3700 1350);
DISPLAY 0.638298 (-3700 1350);
PAINT WHITE (-3700 1350);
FORCENOTE
DCR=2-3,0.27M OHM
(-3700 1300) 0;
DISPLAY LEFT (-3700 1300);
DISPLAY 0.638298 (-3700 1300);
PAINT WHITE (-3700 1300);
FORCENOTE
2ND=CV+15^0TZ01
(-3700 1250) 0;
DISPLAY LEFT (-3700 1250);
DISPLAY 0.638298 (-3700 1250);
PAINT WHITE (-3700 1250);
FORCENOTE
PVDDCR_CPU1_P0_PHASE1
(-7600 5450) 0;
DISPLAY LEFT (-7600 5450);
DISPLAY 1.021277 (-7600 5450);
PAINT WHITE (-7600 5450);
FORCENOTE
ISAT:70A@100C
(-3950 4375) 0;
DISPLAY LEFT (-3950 4375);
DISPLAY 0.638298 (-3950 4375);
PAINT WHITE (-3950 4375);
FORCENOTE
PGL6303.151HLT
(-3950 4425) 0;
DISPLAY LEFT (-3950 4425);
DISPLAY 0.638298 (-3950 4425);
PAINT WHITE (-3950 4425);
FORCENOTE
2ND=CC72703MD39
(-4050 4575) 0;
DISPLAY LEFT (-4050 4575);
DISPLAY 0.638298 (-4050 4575);
PAINT WHITE (-4050 4575);
FORCENOTE
PR82,PR81,PR90,PR89,PR95,PR420 = CS00002JB13
(-2750 5525) 0;
DISPLAY LEFT (-2750 5525);
DISPLAY 0.638298 (-2750 5525);
PAINT WHITE (-2750 5525);
QUIT
